FILE_TYPE = MACRO_DRAWING;
SET COLOR_WIRE YELLOW;
SET COLOR_PROP MONO;
SET COLOR_DOT WHITE;
SET COLOR_ARC YELLOW;
SET COLOR_BODY GREEN;
SET COLOR_NOTE MONO;
SET PROP_DISPLAY VALUE;
SET PAGE_NUMBER P31;
FORCEADD TAP..1
R 2
(-5450 1950);
FORCEPROP 3 LASTPIN (-5400 1950) SIG_NAME P3E_CPU0_PE2_SS_RXP<1>
J 0
(-5390 1960);
DISPLAY 0.659574 (-5390 1960);
PAINT MONO (-5390 1960);
DISPLAY INVISIBLE (-5390 1960);
FORCEPROP 1 LASTPIN (-5400 1950) BN 1
J 2
(-5388 1958);
DISPLAY 0.617021 (-5388 1958);
PAINT PINK (-5388 1958);
FORCEPROP 2 LAST CDS_LIB mstr_standard
J 0
(-5450 1950);
PAINT MONO (-5450 1950);
DISPLAY INVISIBLE (-5450 1950);
FORCEPROP 1 LAST BODY_TYPE PLUMBING
J 2
(-5450 2000);
DISPLAY 1.446809 (-5450 2000);
PAINT GREEN (-5450 2000);
DISPLAY INVISIBLE (-5450 2000);
FORCEPROP 1 LAST HDL_TAP TRUE
J 2
(-5775 1825);
DISPLAY 1.446809 (-5775 1825);
PAINT GREEN (-5775 1825);
DISPLAY INVISIBLE (-5775 1825);
FORCEPROP 1 LAST PATH I10
J 2
(-5448 1950);
DISPLAY 0.872340 (-5448 1950);
PAINT GREEN (-5448 1950);
DISPLAY INVISIBLE (-5448 1950);
FORCEADD TAP..1
R 2
(-5300 2650);
FORCEPROP 3 LASTPIN (-5250 2650) SIG_NAME P3E_CPU0_PE2_SS_RXN<8>
J 0
(-5240 2660);
DISPLAY 0.659574 (-5240 2660);
PAINT MONO (-5240 2660);
DISPLAY INVISIBLE (-5240 2660);
FORCEPROP 1 LASTPIN (-5250 2650) BN 8
J 2
(-5238 2658);
DISPLAY 0.617021 (-5238 2658);
PAINT PINK (-5238 2658);
FORCEPROP 2 LAST CDS_LIB mstr_standard
J 0
(-5300 2650);
PAINT MONO (-5300 2650);
DISPLAY INVISIBLE (-5300 2650);
FORCEPROP 1 LAST BODY_TYPE PLUMBING
J 2
(-5300 2700);
DISPLAY 1.446809 (-5300 2700);
PAINT GREEN (-5300 2700);
DISPLAY INVISIBLE (-5300 2700);
FORCEPROP 1 LAST HDL_TAP TRUE
J 2
(-5625 2525);
DISPLAY 1.446809 (-5625 2525);
PAINT GREEN (-5625 2525);
DISPLAY INVISIBLE (-5625 2525);
FORCEPROP 1 LAST PATH I100
J 2
(-5298 2650);
DISPLAY 0.872340 (-5298 2650);
PAINT GREEN (-5298 2650);
DISPLAY INVISIBLE (-5298 2650);
FORCEADD TAP..1
R 2
(-5450 3000);
FORCEPROP 3 LASTPIN (-5400 3000) SIG_NAME P3E_CPU0_PE2_SS_RXP<10>
J 0
(-5390 3010);
DISPLAY 0.659574 (-5390 3010);
PAINT MONO (-5390 3010);
DISPLAY INVISIBLE (-5390 3010);
FORCEPROP 1 LASTPIN (-5400 3000) BN 10
J 2
(-5388 3008);
DISPLAY 0.617021 (-5388 3008);
PAINT PINK (-5388 3008);
FORCEPROP 2 LAST CDS_LIB mstr_standard
J 0
(-5450 3000);
PAINT MONO (-5450 3000);
DISPLAY INVISIBLE (-5450 3000);
FORCEPROP 1 LAST BODY_TYPE PLUMBING
J 2
(-5450 3050);
DISPLAY 1.446809 (-5450 3050);
PAINT GREEN (-5450 3050);
DISPLAY INVISIBLE (-5450 3050);
FORCEPROP 1 LAST HDL_TAP TRUE
J 2
(-5775 2875);
DISPLAY 1.446809 (-5775 2875);
PAINT GREEN (-5775 2875);
DISPLAY INVISIBLE (-5775 2875);
FORCEPROP 1 LAST PATH I101
J 2
(-5448 3000);
DISPLAY 0.872340 (-5448 3000);
PAINT GREEN (-5448 3000);
DISPLAY INVISIBLE (-5448 3000);
FORCEADD TAP..1
R 2
(-5450 2950);
FORCEPROP 3 LASTPIN (-5400 2950) SIG_NAME P3E_CPU0_PE2_SS_RXP<9>
J 0
(-5390 2960);
DISPLAY 0.659574 (-5390 2960);
PAINT MONO (-5390 2960);
DISPLAY INVISIBLE (-5390 2960);
FORCEPROP 1 LASTPIN (-5400 2950) BN 9
J 2
(-5388 2958);
DISPLAY 0.617021 (-5388 2958);
PAINT PINK (-5388 2958);
FORCEPROP 2 LAST CDS_LIB mstr_standard
J 0
(-5450 2950);
PAINT MONO (-5450 2950);
DISPLAY INVISIBLE (-5450 2950);
FORCEPROP 1 LAST BODY_TYPE PLUMBING
J 2
(-5450 3000);
DISPLAY 1.446809 (-5450 3000);
PAINT GREEN (-5450 3000);
DISPLAY INVISIBLE (-5450 3000);
FORCEPROP 1 LAST HDL_TAP TRUE
J 2
(-5775 2825);
DISPLAY 1.446809 (-5775 2825);
PAINT GREEN (-5775 2825);
DISPLAY INVISIBLE (-5775 2825);
FORCEPROP 1 LAST PATH I102
J 2
(-5448 2950);
DISPLAY 0.872340 (-5448 2950);
PAINT GREEN (-5448 2950);
DISPLAY INVISIBLE (-5448 2950);
FORCEADD TAP..1
R 2
(-5450 2900);
FORCEPROP 3 LASTPIN (-5400 2900) SIG_NAME P3E_CPU0_PE2_SS_RXP<8>
J 0
(-5390 2910);
DISPLAY 0.659574 (-5390 2910);
PAINT MONO (-5390 2910);
DISPLAY INVISIBLE (-5390 2910);
FORCEPROP 1 LASTPIN (-5400 2900) BN 8
J 2
(-5388 2908);
DISPLAY 0.617021 (-5388 2908);
PAINT PINK (-5388 2908);
FORCEPROP 2 LAST CDS_LIB mstr_standard
J 0
(-5450 2900);
PAINT MONO (-5450 2900);
DISPLAY INVISIBLE (-5450 2900);
FORCEPROP 1 LAST BODY_TYPE PLUMBING
J 2
(-5450 2950);
DISPLAY 1.446809 (-5450 2950);
PAINT GREEN (-5450 2950);
DISPLAY INVISIBLE (-5450 2950);
FORCEPROP 1 LAST HDL_TAP TRUE
J 2
(-5775 2775);
DISPLAY 1.446809 (-5775 2775);
PAINT GREEN (-5775 2775);
DISPLAY INVISIBLE (-5775 2775);
FORCEPROP 1 LAST PATH I103
J 2
(-5448 2900);
DISPLAY 0.872340 (-5448 2900);
PAINT GREEN (-5448 2900);
DISPLAY INVISIBLE (-5448 2900);
FORCEADD OFFPAGE..1
(-6600 3700);
FORCEPROP 2 LAST $XR1 245 
J 0
(-6972 3700);
DISPLAY 0.638298 (-6972 3700);
PAINT MONO (-6972 3700);
FORCEPROP 2 LAST $XR0 109 
J 0
(-6852 3700);
DISPLAY 0.638298 (-6852 3700);
PAINT MONO (-6852 3700);
FORCEPROP 2 LAST CDS_LIB mstr_standard
J 0
(-6600 3700);
PAINT MONO (-6600 3700);
DISPLAY INVISIBLE (-6600 3700);
FORCEPROP 1 LAST OFFPAGE TRUE
J 0
(-6275 3575);
DISPLAY 1.170213 (-6275 3575);
PAINT GREEN (-6275 3575);
DISPLAY INVISIBLE (-6275 3575);
FORCEPROP 1 LAST COMMENT_BODY TRUE
J 0
(-6475 3600);
DISPLAY 1.170213 (-6475 3600);
PAINT GREEN (-6475 3600);
DISPLAY INVISIBLE (-6475 3600);
FORCEPROP 2 LAST PATH I104
J 0
(-6850 3750);
DISPLAY 1.021277 (-6850 3750);
PAINT ORANGE (-6850 3750);
DISPLAY INVISIBLE (-6850 3750);
FORCEADD OFFPAGE..1
(-6600 3650);
FORCEPROP 2 LAST $XR1 245 
J 0
(-6972 3650);
DISPLAY 0.638298 (-6972 3650);
PAINT MONO (-6972 3650);
FORCEPROP 2 LAST $XR0 109 
J 0
(-6852 3650);
DISPLAY 0.638298 (-6852 3650);
PAINT MONO (-6852 3650);
FORCEPROP 2 LAST CDS_LIB mstr_standard
J 0
(-6600 3650);
PAINT MONO (-6600 3650);
DISPLAY INVISIBLE (-6600 3650);
FORCEPROP 1 LAST OFFPAGE TRUE
J 0
(-6275 3525);
DISPLAY 1.170213 (-6275 3525);
PAINT GREEN (-6275 3525);
DISPLAY INVISIBLE (-6275 3525);
FORCEPROP 1 LAST COMMENT_BODY TRUE
J 0
(-6475 3550);
DISPLAY 1.170213 (-6475 3550);
PAINT GREEN (-6475 3550);
DISPLAY INVISIBLE (-6475 3550);
FORCEPROP 2 LAST PATH I105
J 0
(-6850 3700);
DISPLAY 1.021277 (-6850 3700);
PAINT ORANGE (-6850 3700);
DISPLAY INVISIBLE (-6850 3700);
FORCEADD SKX_EXT_B..11
(-4025 2600);
FORCEPROP 1 LAST LOCATION U5D1
J 0
(-4725 3800);
DISPLAY 0.617021 (-4725 3800);
PAINT AQUA (-4725 3800);
FORCEPROP 1 LAST PART_NUMBER TBD
J 0
(-4725 1450);
DISPLAY 0.617021 (-4725 1450);
PAINT BLUE (-4725 1450);
FORCEPROP 1 LAST MATERIAL IC
J 0
(-4725 3750);
DISPLAY 0.617021 (-4725 3750);
PAINT SKYBLUE (-4725 3750);
FORCEPROP 2 LASTPIN (-3275 3550) $PN BK5
J 0
(-3265 3560);
DISPLAY 0.617021 (-3265 3560);
PAINT ORANGE (-3265 3560);
FORCEPROP 2 LASTPIN (-3275 3500) $PN BM3
J 0
(-3265 3510);
DISPLAY 0.617021 (-3265 3510);
PAINT ORANGE (-3265 3510);
FORCEPROP 2 LASTPIN (-3275 3450) $PN BN4
J 0
(-3265 3460);
DISPLAY 0.617021 (-3265 3460);
PAINT ORANGE (-3265 3460);
FORCEPROP 2 LASTPIN (-3275 3400) $PN BR4
J 0
(-3265 3410);
DISPLAY 0.617021 (-3265 3410);
PAINT ORANGE (-3265 3410);
FORCEPROP 2 LASTPIN (-3275 3050) $PN BV3
J 0
(-3265 3060);
DISPLAY 0.617021 (-3265 3060);
PAINT ORANGE (-3265 3060);
FORCEPROP 2 LASTPIN (-3275 3000) $PN BY5
J 0
(-3265 3010);
DISPLAY 0.617021 (-3265 3010);
PAINT ORANGE (-3265 3010);
FORCEPROP 2 LASTPIN (-3275 2950) $PN BY3
J 0
(-3265 2960);
DISPLAY 0.617021 (-3265 2960);
PAINT ORANGE (-3265 2960);
FORCEPROP 2 LASTPIN (-3275 2900) $PN CD3
J 0
(-3265 2910);
DISPLAY 0.617021 (-3265 2910);
PAINT ORANGE (-3265 2910);
FORCEPROP 2 LASTPIN (-3275 2550) $PN CE4
J 0
(-3265 2560);
DISPLAY 0.617021 (-3265 2560);
PAINT ORANGE (-3265 2560);
FORCEPROP 2 LASTPIN (-3275 2500) $PN CE2
J 0
(-3265 2510);
DISPLAY 0.617021 (-3265 2510);
PAINT ORANGE (-3265 2510);
FORCEPROP 2 LASTPIN (-3275 2450) $PN CK3
J 0
(-3265 2460);
DISPLAY 0.617021 (-3265 2460);
PAINT ORANGE (-3265 2460);
FORCEPROP 2 LASTPIN (-3275 2400) $PN CK1
J 0
(-3265 2410);
DISPLAY 0.617021 (-3265 2410);
PAINT ORANGE (-3265 2410);
FORCEPROP 2 LASTPIN (-3275 2050) $PN CP3
J 0
(-3265 2060);
DISPLAY 0.617021 (-3265 2060);
PAINT ORANGE (-3265 2060);
FORCEPROP 2 LASTPIN (-3275 2000) $PN CR2
J 0
(-3265 2010);
DISPLAY 0.617021 (-3265 2010);
PAINT ORANGE (-3265 2010);
FORCEPROP 2 LASTPIN (-3275 1950) $PN CU2
J 0
(-3265 1960);
DISPLAY 0.617021 (-3265 1960);
PAINT ORANGE (-3265 1960);
FORCEPROP 2 LASTPIN (-3275 1900) $PN CW4
J 0
(-3265 1910);
DISPLAY 0.617021 (-3265 1910);
PAINT ORANGE (-3265 1910);
FORCEPROP 2 LASTPIN (-3275 3300) $PN BM5
J 0
(-3265 3310);
DISPLAY 0.617021 (-3265 3310);
PAINT ORANGE (-3265 3310);
FORCEPROP 2 LASTPIN (-3275 3250) $PN BL4
J 0
(-3265 3260);
DISPLAY 0.617021 (-3265 3260);
PAINT ORANGE (-3265 3260);
FORCEPROP 2 LASTPIN (-3275 3200) $PN BP5
J 0
(-3265 3210);
DISPLAY 0.617021 (-3265 3210);
PAINT ORANGE (-3265 3210);
FORCEPROP 2 LASTPIN (-3275 3150) $PN BU4
J 0
(-3265 3160);
DISPLAY 0.617021 (-3265 3160);
PAINT ORANGE (-3265 3160);
FORCEPROP 2 LASTPIN (-3275 2800) $PN BW4
J 0
(-3265 2810);
DISPLAY 0.617021 (-3265 2810);
PAINT ORANGE (-3265 2810);
FORCEPROP 2 LASTPIN (-3275 2750) $PN CA4
J 0
(-3265 2760);
DISPLAY 0.617021 (-3265 2760);
PAINT ORANGE (-3265 2760);
FORCEPROP 2 LASTPIN (-3275 2700) $PN CB3
J 0
(-3265 2710);
DISPLAY 0.617021 (-3265 2710);
PAINT ORANGE (-3265 2710);
FORCEPROP 2 LASTPIN (-3275 2650) $PN CC2
J 0
(-3265 2660);
DISPLAY 0.617021 (-3265 2660);
PAINT ORANGE (-3265 2660);
FORCEPROP 2 LASTPIN (-3275 2300) $PN CF3
J 0
(-3265 2310);
DISPLAY 0.617021 (-3265 2310);
PAINT ORANGE (-3265 2310);
FORCEPROP 2 LASTPIN (-3275 2250) $PN CG2
J 0
(-3265 2260);
DISPLAY 0.617021 (-3265 2260);
PAINT ORANGE (-3265 2260);
FORCEPROP 2 LASTPIN (-3275 2200) $PN CL2
J 0
(-3265 2210);
DISPLAY 0.617021 (-3265 2210);
PAINT ORANGE (-3265 2210);
FORCEPROP 2 LASTPIN (-3275 2150) $PN CM1
J 0
(-3265 2160);
DISPLAY 0.617021 (-3265 2160);
PAINT ORANGE (-3265 2160);
FORCEPROP 2 LASTPIN (-3275 1800) $PN CT3
J 0
(-3265 1810);
DISPLAY 0.617021 (-3265 1810);
PAINT ORANGE (-3265 1810);
FORCEPROP 2 LASTPIN (-3275 1750) $PN CT1
J 0
(-3265 1760);
DISPLAY 0.617021 (-3265 1760);
PAINT ORANGE (-3265 1760);
FORCEPROP 2 LASTPIN (-3275 1700) $PN CV3
J 0
(-3265 1710);
DISPLAY 0.617021 (-3265 1710);
PAINT ORANGE (-3265 1710);
FORCEPROP 2 LASTPIN (-3275 1650) $PN CY3
J 0
(-3265 1660);
DISPLAY 0.617021 (-3265 1660);
PAINT ORANGE (-3265 1660);
FORCEPROP 2 LASTPIN (-4775 3550) $PN BJ10
J 2
(-4785 3560);
DISPLAY 0.617021 (-4785 3560);
PAINT ORANGE (-4785 3560);
FORCEPROP 2 LASTPIN (-4775 3500) $PN BJ8
J 2
(-4785 3510);
DISPLAY 0.617021 (-4785 3510);
PAINT ORANGE (-4785 3510);
FORCEPROP 2 LASTPIN (-4775 3450) $PN BM7
J 2
(-4785 3460);
DISPLAY 0.617021 (-4785 3460);
PAINT ORANGE (-4785 3460);
FORCEPROP 2 LASTPIN (-4775 3400) $PN BP9
J 2
(-4785 3410);
DISPLAY 0.617021 (-4785 3410);
PAINT ORANGE (-4785 3410);
FORCEPROP 2 LASTPIN (-4775 3050) $PN BP7
J 2
(-4785 3060);
DISPLAY 0.617021 (-4785 3060);
PAINT ORANGE (-4785 3060);
FORCEPROP 2 LASTPIN (-4775 3000) $PN BU6
J 2
(-4785 3010);
DISPLAY 0.617021 (-4785 3010);
PAINT ORANGE (-4785 3010);
FORCEPROP 2 LASTPIN (-4775 2950) $PN BW8
J 2
(-4785 2960);
DISPLAY 0.617021 (-4785 2960);
PAINT ORANGE (-4785 2960);
FORCEPROP 2 LASTPIN (-4775 2900) $PN BV9
J 2
(-4785 2910);
DISPLAY 0.617021 (-4785 2910);
PAINT ORANGE (-4785 2910);
FORCEPROP 2 LASTPIN (-4775 2550) $PN CC8
J 2
(-4785 2560);
DISPLAY 0.617021 (-4785 2560);
PAINT ORANGE (-4785 2560);
FORCEPROP 2 LASTPIN (-4775 2500) $PN CD7
J 2
(-4785 2510);
DISPLAY 0.617021 (-4785 2510);
PAINT ORANGE (-4785 2510);
FORCEPROP 2 LASTPIN (-4775 2450) $PN CF7
J 2
(-4785 2460);
DISPLAY 0.617021 (-4785 2460);
PAINT ORANGE (-4785 2460);
FORCEPROP 2 LASTPIN (-4775 2400) $PN CH7
J 2
(-4785 2410);
DISPLAY 0.617021 (-4785 2410);
PAINT ORANGE (-4785 2410);
FORCEPROP 2 LASTPIN (-4775 2050) $PN CL6
J 2
(-4785 2060);
DISPLAY 0.617021 (-4785 2060);
PAINT ORANGE (-4785 2060);
FORCEPROP 2 LASTPIN (-4775 2000) $PN CN8
J 2
(-4785 2010);
DISPLAY 0.617021 (-4785 2010);
PAINT ORANGE (-4785 2010);
FORCEPROP 2 LASTPIN (-4775 1950) $PN CM9
J 2
(-4785 1960);
DISPLAY 0.617021 (-4785 1960);
PAINT ORANGE (-4785 1960);
FORCEPROP 2 LASTPIN (-4775 1900) $PN CR8
J 2
(-4785 1910);
DISPLAY 0.617021 (-4785 1910);
PAINT ORANGE (-4785 1910);
FORCEPROP 2 LASTPIN (-4775 3300) $PN BK9
J 2
(-4785 3310);
DISPLAY 0.617021 (-4785 3310);
PAINT ORANGE (-4785 3310);
FORCEPROP 2 LASTPIN (-4775 3250) $PN BL8
J 2
(-4785 3260);
DISPLAY 0.617021 (-4785 3260);
PAINT ORANGE (-4785 3260);
FORCEPROP 2 LASTPIN (-4775 3200) $PN BN8
J 2
(-4785 3210);
DISPLAY 0.617021 (-4785 3210);
PAINT ORANGE (-4785 3210);
FORCEPROP 2 LASTPIN (-4775 3150) $PN BR8
J 2
(-4785 3160);
DISPLAY 0.617021 (-4785 3160);
PAINT ORANGE (-4785 3160);
FORCEPROP 2 LASTPIN (-4775 2800) $PN BT7
J 2
(-4785 2810);
DISPLAY 0.617021 (-4785 2810);
PAINT ORANGE (-4785 2810);
FORCEPROP 2 LASTPIN (-4775 2750) $PN BV7
J 2
(-4785 2760);
DISPLAY 0.617021 (-4785 2760);
PAINT ORANGE (-4785 2760);
FORCEPROP 2 LASTPIN (-4775 2700) $PN BY7
J 2
(-4785 2710);
DISPLAY 0.617021 (-4785 2710);
PAINT ORANGE (-4785 2710);
FORCEPROP 2 LASTPIN (-4775 2650) $PN BY9
J 2
(-4785 2660);
DISPLAY 0.617021 (-4785 2660);
PAINT ORANGE (-4785 2660);
FORCEPROP 2 LASTPIN (-4775 2300) $PN CE8
J 2
(-4785 2310);
DISPLAY 0.617021 (-4785 2310);
PAINT ORANGE (-4785 2310);
FORCEPROP 2 LASTPIN (-4775 2250) $PN CE6
J 2
(-4785 2260);
DISPLAY 0.617021 (-4785 2260);
PAINT ORANGE (-4785 2260);
FORCEPROP 2 LASTPIN (-4775 2200) $PN CG8
J 2
(-4785 2210);
DISPLAY 0.617021 (-4785 2210);
PAINT ORANGE (-4785 2210);
FORCEPROP 2 LASTPIN (-4775 2150) $PN CK7
J 2
(-4785 2160);
DISPLAY 0.617021 (-4785 2160);
PAINT ORANGE (-4785 2160);
FORCEPROP 2 LASTPIN (-4775 1800) $PN CM7
J 2
(-4785 1810);
DISPLAY 0.617021 (-4785 1810);
PAINT ORANGE (-4785 1810);
FORCEPROP 2 LASTPIN (-4775 1750) $PN CP7
J 2
(-4785 1760);
DISPLAY 0.617021 (-4785 1760);
PAINT ORANGE (-4785 1760);
FORCEPROP 2 LASTPIN (-4775 1700) $PN CP9
J 2
(-4785 1710);
DISPLAY 0.617021 (-4785 1710);
PAINT ORANGE (-4785 1710);
FORCEPROP 2 LASTPIN (-4775 1650) $PN CT9
J 2
(-4785 1660);
DISPLAY 0.617021 (-4785 1660);
PAINT ORANGE (-4785 1660);
FORCEPROP 1 LAST PACK_TYPE BGA1
J 0
(-4725 3850);
PAINT SKYBLUE (-4725 3850);
DISPLAY INVISIBLE (-4725 3850);
FORCEPROP 2 LAST CDS_LIB chpset_lib
J 0
(-4025 2600);
PAINT ORANGE (-4025 2600);
DISPLAY INVISIBLE (-4025 2600);
FORCEPROP 2 LAST SEC_TYPE BGA1
J 0
(-4725 3850);
DISPLAY 1.021277 (-4725 3850);
PAINT ORANGE (-4725 3850);
DISPLAY INVISIBLE (-4725 3850);
FORCEPROP 2 LAST SEC 11
J 0
(-4725 3850);
DISPLAY 0.680851 (-4725 3850);
PAINT MONO (-4725 3850);
DISPLAY INVISIBLE (-4725 3850);
FORCEPROP 2 LAST CDS_LOCATION U5D1
J 0
(-4725 3800);
DISPLAY 0.617021 (-4725 3800);
PAINT AQUA (-4725 3800);
DISPLAY INVISIBLE (-4725 3800);
FORCEPROP 1 LAST PATH I106
J 0
(-4025 3750);
PAINT GREEN (-4025 3750);
DISPLAY INVISIBLE (-4025 3750);
FORCEPROP 0 LAST ROOM CPU0
J 0
(-4725 3900);
DISPLAY 1.021277 (-4725 3900);
PAINT ORANGE (-4725 3900);
DISPLAY INVISIBLE (-4725 3900);
FORCEADD TAP..1
R 2
(-5450 2000);
FORCEPROP 3 LASTPIN (-5400 2000) SIG_NAME P3E_CPU0_PE2_SS_RXP<2>
J 0
(-5390 2010);
DISPLAY 0.659574 (-5390 2010);
PAINT MONO (-5390 2010);
DISPLAY INVISIBLE (-5390 2010);
FORCEPROP 1 LASTPIN (-5400 2000) BN 2
J 2
(-5388 2008);
DISPLAY 0.617021 (-5388 2008);
PAINT PINK (-5388 2008);
FORCEPROP 2 LAST CDS_LIB mstr_standard
J 0
(-5450 2000);
PAINT MONO (-5450 2000);
DISPLAY INVISIBLE (-5450 2000);
FORCEPROP 1 LAST BODY_TYPE PLUMBING
J 2
(-5450 2050);
DISPLAY 1.446809 (-5450 2050);
PAINT GREEN (-5450 2050);
DISPLAY INVISIBLE (-5450 2050);
FORCEPROP 1 LAST HDL_TAP TRUE
J 2
(-5775 1875);
DISPLAY 1.446809 (-5775 1875);
PAINT GREEN (-5775 1875);
DISPLAY INVISIBLE (-5775 1875);
FORCEPROP 1 LAST PATH I11
J 2
(-5448 2000);
DISPLAY 0.872340 (-5448 2000);
PAINT GREEN (-5448 2000);
DISPLAY INVISIBLE (-5448 2000);
FORCEADD TAP..1
R 2
(-5450 2400);
FORCEPROP 3 LASTPIN (-5400 2400) SIG_NAME P3E_CPU0_PE2_SS_RXP<4>
J 0
(-5390 2410);
DISPLAY 0.659574 (-5390 2410);
PAINT MONO (-5390 2410);
DISPLAY INVISIBLE (-5390 2410);
FORCEPROP 1 LASTPIN (-5400 2400) BN 4
J 2
(-5388 2408);
DISPLAY 0.617021 (-5388 2408);
PAINT PINK (-5388 2408);
FORCEPROP 2 LAST CDS_LIB mstr_standard
J 0
(-5450 2400);
PAINT MONO (-5450 2400);
DISPLAY INVISIBLE (-5450 2400);
FORCEPROP 1 LAST BODY_TYPE PLUMBING
J 2
(-5450 2450);
DISPLAY 1.446809 (-5450 2450);
PAINT GREEN (-5450 2450);
DISPLAY INVISIBLE (-5450 2450);
FORCEPROP 1 LAST HDL_TAP TRUE
J 2
(-5775 2275);
DISPLAY 1.446809 (-5775 2275);
PAINT GREEN (-5775 2275);
DISPLAY INVISIBLE (-5775 2275);
FORCEPROP 1 LAST PATH I12
J 2
(-5448 2400);
DISPLAY 0.872340 (-5448 2400);
PAINT GREEN (-5448 2400);
DISPLAY INVISIBLE (-5448 2400);
FORCEADD TAP..1
R 2
(-5300 2150);
FORCEPROP 3 LASTPIN (-5250 2150) SIG_NAME P3E_CPU0_PE2_SS_RXN<4>
J 0
(-5240 2160);
DISPLAY 0.659574 (-5240 2160);
PAINT MONO (-5240 2160);
DISPLAY INVISIBLE (-5240 2160);
FORCEPROP 1 LASTPIN (-5250 2150) BN 4
J 2
(-5238 2158);
DISPLAY 0.617021 (-5238 2158);
PAINT PINK (-5238 2158);
FORCEPROP 2 LAST CDS_LIB mstr_standard
J 0
(-5300 2150);
PAINT MONO (-5300 2150);
DISPLAY INVISIBLE (-5300 2150);
FORCEPROP 1 LAST BODY_TYPE PLUMBING
J 2
(-5300 2200);
DISPLAY 1.446809 (-5300 2200);
PAINT GREEN (-5300 2200);
DISPLAY INVISIBLE (-5300 2200);
FORCEPROP 1 LAST HDL_TAP TRUE
J 2
(-5625 2025);
DISPLAY 1.446809 (-5625 2025);
PAINT GREEN (-5625 2025);
DISPLAY INVISIBLE (-5625 2025);
FORCEPROP 1 LAST PATH I13
J 2
(-5298 2150);
DISPLAY 0.872340 (-5298 2150);
PAINT GREEN (-5298 2150);
DISPLAY INVISIBLE (-5298 2150);
FORCEADD TAP..1
R 2
(-5300 2250);
FORCEPROP 3 LASTPIN (-5250 2250) SIG_NAME P3E_CPU0_PE2_SS_RXN<6>
J 0
(-5240 2260);
DISPLAY 0.659574 (-5240 2260);
PAINT MONO (-5240 2260);
DISPLAY INVISIBLE (-5240 2260);
FORCEPROP 1 LASTPIN (-5250 2250) BN 6
J 2
(-5238 2258);
DISPLAY 0.617021 (-5238 2258);
PAINT PINK (-5238 2258);
FORCEPROP 2 LAST CDS_LIB mstr_standard
J 0
(-5300 2250);
PAINT MONO (-5300 2250);
DISPLAY INVISIBLE (-5300 2250);
FORCEPROP 1 LAST BODY_TYPE PLUMBING
J 2
(-5300 2300);
DISPLAY 1.446809 (-5300 2300);
PAINT GREEN (-5300 2300);
DISPLAY INVISIBLE (-5300 2300);
FORCEPROP 1 LAST HDL_TAP TRUE
J 2
(-5625 2125);
DISPLAY 1.446809 (-5625 2125);
PAINT GREEN (-5625 2125);
DISPLAY INVISIBLE (-5625 2125);
FORCEPROP 1 LAST PATH I14
J 2
(-5298 2250);
DISPLAY 0.872340 (-5298 2250);
PAINT GREEN (-5298 2250);
DISPLAY INVISIBLE (-5298 2250);
FORCEADD TAP..1
R 2
(-5300 2300);
FORCEPROP 3 LASTPIN (-5250 2300) SIG_NAME P3E_CPU0_PE2_SS_RXN<7>
J 0
(-5240 2310);
DISPLAY 0.659574 (-5240 2310);
PAINT MONO (-5240 2310);
DISPLAY INVISIBLE (-5240 2310);
FORCEPROP 1 LASTPIN (-5250 2300) BN 7
J 2
(-5238 2308);
DISPLAY 0.617021 (-5238 2308);
PAINT PINK (-5238 2308);
FORCEPROP 2 LAST CDS_LIB mstr_standard
J 0
(-5300 2300);
PAINT MONO (-5300 2300);
DISPLAY INVISIBLE (-5300 2300);
FORCEPROP 1 LAST BODY_TYPE PLUMBING
J 2
(-5300 2350);
DISPLAY 1.446809 (-5300 2350);
PAINT GREEN (-5300 2350);
DISPLAY INVISIBLE (-5300 2350);
FORCEPROP 1 LAST HDL_TAP TRUE
J 2
(-5625 2175);
DISPLAY 1.446809 (-5625 2175);
PAINT GREEN (-5625 2175);
DISPLAY INVISIBLE (-5625 2175);
FORCEPROP 1 LAST PATH I15
J 2
(-5298 2300);
DISPLAY 0.872340 (-5298 2300);
PAINT GREEN (-5298 2300);
DISPLAY INVISIBLE (-5298 2300);
FORCEADD TAP..1
R 2
(-5300 2200);
FORCEPROP 3 LASTPIN (-5250 2200) SIG_NAME P3E_CPU0_PE2_SS_RXN<5>
J 0
(-5240 2210);
DISPLAY 0.659574 (-5240 2210);
PAINT MONO (-5240 2210);
DISPLAY INVISIBLE (-5240 2210);
FORCEPROP 1 LASTPIN (-5250 2200) BN 5
J 2
(-5238 2208);
DISPLAY 0.617021 (-5238 2208);
PAINT PINK (-5238 2208);
FORCEPROP 2 LAST CDS_LIB mstr_standard
J 0
(-5300 2200);
PAINT MONO (-5300 2200);
DISPLAY INVISIBLE (-5300 2200);
FORCEPROP 1 LAST BODY_TYPE PLUMBING
J 2
(-5300 2250);
DISPLAY 1.446809 (-5300 2250);
PAINT GREEN (-5300 2250);
DISPLAY INVISIBLE (-5300 2250);
FORCEPROP 1 LAST HDL_TAP TRUE
J 2
(-5625 2075);
DISPLAY 1.446809 (-5625 2075);
PAINT GREEN (-5625 2075);
DISPLAY INVISIBLE (-5625 2075);
FORCEPROP 1 LAST PATH I16
J 2
(-5298 2200);
DISPLAY 0.872340 (-5298 2200);
PAINT GREEN (-5298 2200);
DISPLAY INVISIBLE (-5298 2200);
FORCEADD TAP..1
R 2
(-5450 2550);
FORCEPROP 3 LASTPIN (-5400 2550) SIG_NAME P3E_CPU0_PE2_SS_RXP<7>
J 0
(-5390 2560);
DISPLAY 0.659574 (-5390 2560);
PAINT MONO (-5390 2560);
DISPLAY INVISIBLE (-5390 2560);
FORCEPROP 1 LASTPIN (-5400 2550) BN 7
J 2
(-5388 2558);
DISPLAY 0.617021 (-5388 2558);
PAINT PINK (-5388 2558);
FORCEPROP 2 LAST CDS_LIB mstr_standard
J 0
(-5450 2550);
PAINT MONO (-5450 2550);
DISPLAY INVISIBLE (-5450 2550);
FORCEPROP 1 LAST BODY_TYPE PLUMBING
J 2
(-5450 2600);
DISPLAY 1.446809 (-5450 2600);
PAINT GREEN (-5450 2600);
DISPLAY INVISIBLE (-5450 2600);
FORCEPROP 1 LAST HDL_TAP TRUE
J 2
(-5775 2425);
DISPLAY 1.446809 (-5775 2425);
PAINT GREEN (-5775 2425);
DISPLAY INVISIBLE (-5775 2425);
FORCEPROP 1 LAST PATH I17
J 2
(-5448 2550);
DISPLAY 0.872340 (-5448 2550);
PAINT GREEN (-5448 2550);
DISPLAY INVISIBLE (-5448 2550);
FORCEADD TAP..1
R 2
(-5450 2450);
FORCEPROP 3 LASTPIN (-5400 2450) SIG_NAME P3E_CPU0_PE2_SS_RXP<5>
J 0
(-5390 2460);
DISPLAY 0.659574 (-5390 2460);
PAINT MONO (-5390 2460);
DISPLAY INVISIBLE (-5390 2460);
FORCEPROP 1 LASTPIN (-5400 2450) BN 5
J 2
(-5388 2458);
DISPLAY 0.617021 (-5388 2458);
PAINT PINK (-5388 2458);
FORCEPROP 2 LAST CDS_LIB mstr_standard
J 0
(-5450 2450);
PAINT MONO (-5450 2450);
DISPLAY INVISIBLE (-5450 2450);
FORCEPROP 1 LAST BODY_TYPE PLUMBING
J 2
(-5450 2500);
DISPLAY 1.446809 (-5450 2500);
PAINT GREEN (-5450 2500);
DISPLAY INVISIBLE (-5450 2500);
FORCEPROP 1 LAST HDL_TAP TRUE
J 2
(-5775 2325);
DISPLAY 1.446809 (-5775 2325);
PAINT GREEN (-5775 2325);
DISPLAY INVISIBLE (-5775 2325);
FORCEPROP 1 LAST PATH I18
J 2
(-5448 2450);
DISPLAY 0.872340 (-5448 2450);
PAINT GREEN (-5448 2450);
DISPLAY INVISIBLE (-5448 2450);
FORCEADD TAP..1
R 2
(-5450 2500);
FORCEPROP 3 LASTPIN (-5400 2500) SIG_NAME P3E_CPU0_PE2_SS_RXP<6>
J 0
(-5390 2510);
DISPLAY 0.659574 (-5390 2510);
PAINT MONO (-5390 2510);
DISPLAY INVISIBLE (-5390 2510);
FORCEPROP 1 LASTPIN (-5400 2500) BN 6
J 2
(-5388 2508);
DISPLAY 0.617021 (-5388 2508);
PAINT PINK (-5388 2508);
FORCEPROP 2 LAST CDS_LIB mstr_standard
J 0
(-5450 2500);
PAINT MONO (-5450 2500);
DISPLAY INVISIBLE (-5450 2500);
FORCEPROP 1 LAST BODY_TYPE PLUMBING
J 2
(-5450 2550);
DISPLAY 1.446809 (-5450 2550);
PAINT GREEN (-5450 2550);
DISPLAY INVISIBLE (-5450 2550);
FORCEPROP 1 LAST HDL_TAP TRUE
J 2
(-5775 2375);
DISPLAY 1.446809 (-5775 2375);
PAINT GREEN (-5775 2375);
DISPLAY INVISIBLE (-5775 2375);
FORCEPROP 1 LAST PATH I19
J 2
(-5448 2500);
DISPLAY 0.872340 (-5448 2500);
PAINT GREEN (-5448 2500);
DISPLAY INVISIBLE (-5448 2500);
FORCEADD TAP..1
R 2
(-5300 1650);
FORCEPROP 3 LASTPIN (-5250 1650) SIG_NAME P3E_CPU0_PE2_SS_RXN<0>
J 0
(-5240 1660);
DISPLAY 0.659574 (-5240 1660);
PAINT MONO (-5240 1660);
DISPLAY INVISIBLE (-5240 1660);
FORCEPROP 1 LASTPIN (-5250 1650) BN 0
J 2
(-5238 1658);
DISPLAY 0.617021 (-5238 1658);
PAINT PINK (-5238 1658);
FORCEPROP 2 LAST CDS_LIB mstr_standard
J 0
(-5300 1650);
PAINT MONO (-5300 1650);
DISPLAY INVISIBLE (-5300 1650);
FORCEPROP 1 LAST BODY_TYPE PLUMBING
J 2
(-5300 1700);
DISPLAY 1.446809 (-5300 1700);
PAINT GREEN (-5300 1700);
DISPLAY INVISIBLE (-5300 1700);
FORCEPROP 1 LAST HDL_TAP TRUE
J 2
(-5625 1525);
DISPLAY 1.446809 (-5625 1525);
PAINT GREEN (-5625 1525);
DISPLAY INVISIBLE (-5625 1525);
FORCEPROP 1 LAST PATH I3
J 2
(-5298 1650);
DISPLAY 0.872340 (-5298 1650);
PAINT GREEN (-5298 1650);
DISPLAY INVISIBLE (-5298 1650);
FORCEADD TAP..1
(-2675 1650);
FORCEPROP 3 LASTPIN (-2725 1650) SIG_NAME P3E_CPU0_PE2_SS_TXN<0>
J 0
(-2715 1660);
DISPLAY 0.659574 (-2715 1660);
PAINT MONO (-2715 1660);
DISPLAY INVISIBLE (-2715 1660);
FORCEPROP 1 LASTPIN (-2725 1650) BN 0
J 0
(-2737 1658);
DISPLAY 0.617021 (-2737 1658);
PAINT PINK (-2737 1658);
FORCEPROP 2 LAST CDS_LIB mstr_standard
J 2
(-2675 1650);
PAINT MONO (-2675 1650);
DISPLAY INVISIBLE (-2675 1650);
FORCEPROP 1 LAST BODY_TYPE PLUMBING
J 0
(-2675 1700);
DISPLAY 1.446809 (-2675 1700);
PAINT GREEN (-2675 1700);
DISPLAY INVISIBLE (-2675 1700);
FORCEPROP 1 LAST HDL_TAP TRUE
J 0
(-2350 1525);
DISPLAY 1.446809 (-2350 1525);
PAINT GREEN (-2350 1525);
DISPLAY INVISIBLE (-2350 1525);
FORCEPROP 1 LAST PATH I36
J 0
(-2677 1650);
DISPLAY 0.872340 (-2677 1650);
PAINT GREEN (-2677 1650);
DISPLAY INVISIBLE (-2677 1650);
FORCEADD TAP..1
(-2825 1900);
FORCEPROP 3 LASTPIN (-2875 1900) SIG_NAME P3E_CPU0_PE2_SS_TXP<0>
J 0
(-2865 1910);
DISPLAY 0.659574 (-2865 1910);
PAINT MONO (-2865 1910);
DISPLAY INVISIBLE (-2865 1910);
FORCEPROP 1 LASTPIN (-2875 1900) BN 0
J 0
(-2887 1908);
DISPLAY 0.617021 (-2887 1908);
PAINT PINK (-2887 1908);
FORCEPROP 2 LAST CDS_LIB mstr_standard
J 2
(-2825 1900);
PAINT MONO (-2825 1900);
DISPLAY INVISIBLE (-2825 1900);
FORCEPROP 1 LAST BODY_TYPE PLUMBING
J 0
(-2825 1950);
DISPLAY 1.446809 (-2825 1950);
PAINT GREEN (-2825 1950);
DISPLAY INVISIBLE (-2825 1950);
FORCEPROP 1 LAST HDL_TAP TRUE
J 0
(-2500 1775);
DISPLAY 1.446809 (-2500 1775);
PAINT GREEN (-2500 1775);
DISPLAY INVISIBLE (-2500 1775);
FORCEPROP 1 LAST PATH I37
J 0
(-2827 1900);
DISPLAY 0.872340 (-2827 1900);
PAINT GREEN (-2827 1900);
DISPLAY INVISIBLE (-2827 1900);
FORCEADD TAP..1
(-2675 1700);
FORCEPROP 3 LASTPIN (-2725 1700) SIG_NAME P3E_CPU0_PE2_SS_TXN<1>
J 0
(-2715 1710);
DISPLAY 0.659574 (-2715 1710);
PAINT MONO (-2715 1710);
DISPLAY INVISIBLE (-2715 1710);
FORCEPROP 1 LASTPIN (-2725 1700) BN 1
J 0
(-2737 1708);
DISPLAY 0.617021 (-2737 1708);
PAINT PINK (-2737 1708);
FORCEPROP 2 LAST CDS_LIB mstr_standard
J 2
(-2675 1700);
PAINT MONO (-2675 1700);
DISPLAY INVISIBLE (-2675 1700);
FORCEPROP 1 LAST BODY_TYPE PLUMBING
J 0
(-2675 1750);
DISPLAY 1.446809 (-2675 1750);
PAINT GREEN (-2675 1750);
DISPLAY INVISIBLE (-2675 1750);
FORCEPROP 1 LAST HDL_TAP TRUE
J 0
(-2350 1575);
DISPLAY 1.446809 (-2350 1575);
PAINT GREEN (-2350 1575);
DISPLAY INVISIBLE (-2350 1575);
FORCEPROP 1 LAST PATH I38
J 0
(-2677 1700);
DISPLAY 0.872340 (-2677 1700);
PAINT GREEN (-2677 1700);
DISPLAY INVISIBLE (-2677 1700);
FORCEADD TAP..1
(-2675 1750);
FORCEPROP 3 LASTPIN (-2725 1750) SIG_NAME P3E_CPU0_PE2_SS_TXN<2>
J 0
(-2715 1760);
DISPLAY 0.659574 (-2715 1760);
PAINT MONO (-2715 1760);
DISPLAY INVISIBLE (-2715 1760);
FORCEPROP 1 LASTPIN (-2725 1750) BN 2
J 0
(-2737 1758);
DISPLAY 0.617021 (-2737 1758);
PAINT PINK (-2737 1758);
FORCEPROP 2 LAST CDS_LIB mstr_standard
J 2
(-2675 1750);
PAINT MONO (-2675 1750);
DISPLAY INVISIBLE (-2675 1750);
FORCEPROP 1 LAST BODY_TYPE PLUMBING
J 0
(-2675 1800);
DISPLAY 1.446809 (-2675 1800);
PAINT GREEN (-2675 1800);
DISPLAY INVISIBLE (-2675 1800);
FORCEPROP 1 LAST HDL_TAP TRUE
J 0
(-2350 1625);
DISPLAY 1.446809 (-2350 1625);
PAINT GREEN (-2350 1625);
DISPLAY INVISIBLE (-2350 1625);
FORCEPROP 1 LAST PATH I39
J 0
(-2677 1750);
DISPLAY 0.872340 (-2677 1750);
PAINT GREEN (-2677 1750);
DISPLAY INVISIBLE (-2677 1750);
FORCEADD TAP..1
R 2
(-5300 1700);
FORCEPROP 3 LASTPIN (-5250 1700) SIG_NAME P3E_CPU0_PE2_SS_RXN<1>
J 0
(-5240 1710);
DISPLAY 0.659574 (-5240 1710);
PAINT MONO (-5240 1710);
DISPLAY INVISIBLE (-5240 1710);
FORCEPROP 1 LASTPIN (-5250 1700) BN 1
J 2
(-5238 1708);
DISPLAY 0.617021 (-5238 1708);
PAINT PINK (-5238 1708);
FORCEPROP 2 LAST CDS_LIB mstr_standard
J 0
(-5300 1700);
PAINT MONO (-5300 1700);
DISPLAY INVISIBLE (-5300 1700);
FORCEPROP 1 LAST BODY_TYPE PLUMBING
J 2
(-5300 1750);
DISPLAY 1.446809 (-5300 1750);
PAINT GREEN (-5300 1750);
DISPLAY INVISIBLE (-5300 1750);
FORCEPROP 1 LAST HDL_TAP TRUE
J 2
(-5625 1575);
DISPLAY 1.446809 (-5625 1575);
PAINT GREEN (-5625 1575);
DISPLAY INVISIBLE (-5625 1575);
FORCEPROP 1 LAST PATH I4
J 2
(-5298 1700);
DISPLAY 0.872340 (-5298 1700);
PAINT GREEN (-5298 1700);
DISPLAY INVISIBLE (-5298 1700);
FORCEADD TAP..1
(-2675 1800);
FORCEPROP 3 LASTPIN (-2725 1800) SIG_NAME P3E_CPU0_PE2_SS_TXN<3>
J 0
(-2715 1810);
DISPLAY 0.659574 (-2715 1810);
PAINT MONO (-2715 1810);
DISPLAY INVISIBLE (-2715 1810);
FORCEPROP 1 LASTPIN (-2725 1800) BN 3
J 0
(-2737 1808);
DISPLAY 0.617021 (-2737 1808);
PAINT PINK (-2737 1808);
FORCEPROP 2 LAST CDS_LIB mstr_standard
J 2
(-2675 1800);
PAINT MONO (-2675 1800);
DISPLAY INVISIBLE (-2675 1800);
FORCEPROP 1 LAST BODY_TYPE PLUMBING
J 0
(-2675 1850);
DISPLAY 1.446809 (-2675 1850);
PAINT GREEN (-2675 1850);
DISPLAY INVISIBLE (-2675 1850);
FORCEPROP 1 LAST HDL_TAP TRUE
J 0
(-2350 1675);
DISPLAY 1.446809 (-2350 1675);
PAINT GREEN (-2350 1675);
DISPLAY INVISIBLE (-2350 1675);
FORCEPROP 1 LAST PATH I40
J 0
(-2677 1800);
DISPLAY 0.872340 (-2677 1800);
PAINT GREEN (-2677 1800);
DISPLAY INVISIBLE (-2677 1800);
FORCEADD TAP..1
(-2825 1950);
FORCEPROP 3 LASTPIN (-2875 1950) SIG_NAME P3E_CPU0_PE2_SS_TXP<1>
J 0
(-2865 1960);
DISPLAY 0.659574 (-2865 1960);
PAINT MONO (-2865 1960);
DISPLAY INVISIBLE (-2865 1960);
FORCEPROP 1 LASTPIN (-2875 1950) BN 1
J 0
(-2887 1958);
DISPLAY 0.617021 (-2887 1958);
PAINT PINK (-2887 1958);
FORCEPROP 2 LAST CDS_LIB mstr_standard
J 2
(-2825 1950);
PAINT MONO (-2825 1950);
DISPLAY INVISIBLE (-2825 1950);
FORCEPROP 1 LAST BODY_TYPE PLUMBING
J 0
(-2825 2000);
DISPLAY 1.446809 (-2825 2000);
PAINT GREEN (-2825 2000);
DISPLAY INVISIBLE (-2825 2000);
FORCEPROP 1 LAST HDL_TAP TRUE
J 0
(-2500 1825);
DISPLAY 1.446809 (-2500 1825);
PAINT GREEN (-2500 1825);
DISPLAY INVISIBLE (-2500 1825);
FORCEPROP 1 LAST PATH I41
J 0
(-2827 1950);
DISPLAY 0.872340 (-2827 1950);
PAINT GREEN (-2827 1950);
DISPLAY INVISIBLE (-2827 1950);
FORCEADD TAP..1
(-2825 2000);
FORCEPROP 3 LASTPIN (-2875 2000) SIG_NAME P3E_CPU0_PE2_SS_TXP<2>
J 0
(-2865 2010);
DISPLAY 0.659574 (-2865 2010);
PAINT MONO (-2865 2010);
DISPLAY INVISIBLE (-2865 2010);
FORCEPROP 1 LASTPIN (-2875 2000) BN 2
J 0
(-2887 2008);
DISPLAY 0.617021 (-2887 2008);
PAINT PINK (-2887 2008);
FORCEPROP 2 LAST CDS_LIB mstr_standard
J 2
(-2825 2000);
PAINT MONO (-2825 2000);
DISPLAY INVISIBLE (-2825 2000);
FORCEPROP 1 LAST BODY_TYPE PLUMBING
J 0
(-2825 2050);
DISPLAY 1.446809 (-2825 2050);
PAINT GREEN (-2825 2050);
DISPLAY INVISIBLE (-2825 2050);
FORCEPROP 1 LAST HDL_TAP TRUE
J 0
(-2500 1875);
DISPLAY 1.446809 (-2500 1875);
PAINT GREEN (-2500 1875);
DISPLAY INVISIBLE (-2500 1875);
FORCEPROP 1 LAST PATH I42
J 0
(-2827 2000);
DISPLAY 0.872340 (-2827 2000);
PAINT GREEN (-2827 2000);
DISPLAY INVISIBLE (-2827 2000);
FORCEADD TAP..1
(-2825 2050);
FORCEPROP 3 LASTPIN (-2875 2050) SIG_NAME P3E_CPU0_PE2_SS_TXP<3>
J 0
(-2865 2060);
DISPLAY 0.659574 (-2865 2060);
PAINT MONO (-2865 2060);
DISPLAY INVISIBLE (-2865 2060);
FORCEPROP 1 LASTPIN (-2875 2050) BN 3
J 0
(-2887 2058);
DISPLAY 0.617021 (-2887 2058);
PAINT PINK (-2887 2058);
FORCEPROP 2 LAST CDS_LIB mstr_standard
J 2
(-2825 2050);
PAINT MONO (-2825 2050);
DISPLAY INVISIBLE (-2825 2050);
FORCEPROP 1 LAST BODY_TYPE PLUMBING
J 0
(-2825 2100);
DISPLAY 1.446809 (-2825 2100);
PAINT GREEN (-2825 2100);
DISPLAY INVISIBLE (-2825 2100);
FORCEPROP 1 LAST HDL_TAP TRUE
J 0
(-2500 1925);
DISPLAY 1.446809 (-2500 1925);
PAINT GREEN (-2500 1925);
DISPLAY INVISIBLE (-2500 1925);
FORCEPROP 1 LAST PATH I43
J 0
(-2827 2050);
DISPLAY 0.872340 (-2827 2050);
PAINT GREEN (-2827 2050);
DISPLAY INVISIBLE (-2827 2050);
FORCEADD TAP..1
(-2675 2150);
FORCEPROP 3 LASTPIN (-2725 2150) SIG_NAME P3E_CPU0_PE2_SS_TXN<4>
J 0
(-2715 2160);
DISPLAY 0.659574 (-2715 2160);
PAINT MONO (-2715 2160);
DISPLAY INVISIBLE (-2715 2160);
FORCEPROP 1 LASTPIN (-2725 2150) BN 4
J 0
(-2737 2158);
DISPLAY 0.617021 (-2737 2158);
PAINT PINK (-2737 2158);
FORCEPROP 2 LAST CDS_LIB mstr_standard
J 2
(-2675 2150);
PAINT MONO (-2675 2150);
DISPLAY INVISIBLE (-2675 2150);
FORCEPROP 1 LAST BODY_TYPE PLUMBING
J 0
(-2675 2200);
DISPLAY 1.446809 (-2675 2200);
PAINT GREEN (-2675 2200);
DISPLAY INVISIBLE (-2675 2200);
FORCEPROP 1 LAST HDL_TAP TRUE
J 0
(-2350 2025);
DISPLAY 1.446809 (-2350 2025);
PAINT GREEN (-2350 2025);
DISPLAY INVISIBLE (-2350 2025);
FORCEPROP 1 LAST PATH I44
J 0
(-2677 2150);
DISPLAY 0.872340 (-2677 2150);
PAINT GREEN (-2677 2150);
DISPLAY INVISIBLE (-2677 2150);
FORCEADD TAP..1
(-2825 2400);
FORCEPROP 3 LASTPIN (-2875 2400) SIG_NAME P3E_CPU0_PE2_SS_TXP<4>
J 0
(-2865 2410);
DISPLAY 0.659574 (-2865 2410);
PAINT MONO (-2865 2410);
DISPLAY INVISIBLE (-2865 2410);
FORCEPROP 1 LASTPIN (-2875 2400) BN 4
J 0
(-2887 2408);
DISPLAY 0.617021 (-2887 2408);
PAINT PINK (-2887 2408);
FORCEPROP 2 LAST CDS_LIB mstr_standard
J 2
(-2825 2400);
PAINT MONO (-2825 2400);
DISPLAY INVISIBLE (-2825 2400);
FORCEPROP 1 LAST BODY_TYPE PLUMBING
J 0
(-2825 2450);
DISPLAY 1.446809 (-2825 2450);
PAINT GREEN (-2825 2450);
DISPLAY INVISIBLE (-2825 2450);
FORCEPROP 1 LAST HDL_TAP TRUE
J 0
(-2500 2275);
DISPLAY 1.446809 (-2500 2275);
PAINT GREEN (-2500 2275);
DISPLAY INVISIBLE (-2500 2275);
FORCEPROP 1 LAST PATH I45
J 0
(-2827 2400);
DISPLAY 0.872340 (-2827 2400);
PAINT GREEN (-2827 2400);
DISPLAY INVISIBLE (-2827 2400);
FORCEADD TAP..1
(-2675 2200);
FORCEPROP 3 LASTPIN (-2725 2200) SIG_NAME P3E_CPU0_PE2_SS_TXN<5>
J 0
(-2715 2210);
DISPLAY 0.659574 (-2715 2210);
PAINT MONO (-2715 2210);
DISPLAY INVISIBLE (-2715 2210);
FORCEPROP 1 LASTPIN (-2725 2200) BN 5
J 0
(-2737 2208);
DISPLAY 0.617021 (-2737 2208);
PAINT PINK (-2737 2208);
FORCEPROP 2 LAST CDS_LIB mstr_standard
J 2
(-2675 2200);
PAINT MONO (-2675 2200);
DISPLAY INVISIBLE (-2675 2200);
FORCEPROP 1 LAST BODY_TYPE PLUMBING
J 0
(-2675 2250);
DISPLAY 1.446809 (-2675 2250);
PAINT GREEN (-2675 2250);
DISPLAY INVISIBLE (-2675 2250);
FORCEPROP 1 LAST HDL_TAP TRUE
J 0
(-2350 2075);
DISPLAY 1.446809 (-2350 2075);
PAINT GREEN (-2350 2075);
DISPLAY INVISIBLE (-2350 2075);
FORCEPROP 1 LAST PATH I46
J 0
(-2677 2200);
DISPLAY 0.872340 (-2677 2200);
PAINT GREEN (-2677 2200);
DISPLAY INVISIBLE (-2677 2200);
FORCEADD TAP..1
(-2675 2300);
FORCEPROP 3 LASTPIN (-2725 2300) SIG_NAME P3E_CPU0_PE2_SS_TXN<7>
J 0
(-2715 2310);
DISPLAY 0.659574 (-2715 2310);
PAINT MONO (-2715 2310);
DISPLAY INVISIBLE (-2715 2310);
FORCEPROP 1 LASTPIN (-2725 2300) BN 7
J 0
(-2737 2308);
DISPLAY 0.617021 (-2737 2308);
PAINT PINK (-2737 2308);
FORCEPROP 2 LAST CDS_LIB mstr_standard
J 2
(-2675 2300);
PAINT MONO (-2675 2300);
DISPLAY INVISIBLE (-2675 2300);
FORCEPROP 1 LAST BODY_TYPE PLUMBING
J 0
(-2675 2350);
DISPLAY 1.446809 (-2675 2350);
PAINT GREEN (-2675 2350);
DISPLAY INVISIBLE (-2675 2350);
FORCEPROP 1 LAST HDL_TAP TRUE
J 0
(-2350 2175);
DISPLAY 1.446809 (-2350 2175);
PAINT GREEN (-2350 2175);
DISPLAY INVISIBLE (-2350 2175);
FORCEPROP 1 LAST PATH I47
J 0
(-2677 2300);
DISPLAY 0.872340 (-2677 2300);
PAINT GREEN (-2677 2300);
DISPLAY INVISIBLE (-2677 2300);
FORCEADD TAP..1
(-2675 2250);
FORCEPROP 3 LASTPIN (-2725 2250) SIG_NAME P3E_CPU0_PE2_SS_TXN<6>
J 0
(-2715 2260);
DISPLAY 0.659574 (-2715 2260);
PAINT MONO (-2715 2260);
DISPLAY INVISIBLE (-2715 2260);
FORCEPROP 1 LASTPIN (-2725 2250) BN 6
J 0
(-2737 2258);
DISPLAY 0.617021 (-2737 2258);
PAINT PINK (-2737 2258);
FORCEPROP 2 LAST CDS_LIB mstr_standard
J 2
(-2675 2250);
PAINT MONO (-2675 2250);
DISPLAY INVISIBLE (-2675 2250);
FORCEPROP 1 LAST BODY_TYPE PLUMBING
J 0
(-2675 2300);
DISPLAY 1.446809 (-2675 2300);
PAINT GREEN (-2675 2300);
DISPLAY INVISIBLE (-2675 2300);
FORCEPROP 1 LAST HDL_TAP TRUE
J 0
(-2350 2125);
DISPLAY 1.446809 (-2350 2125);
PAINT GREEN (-2350 2125);
DISPLAY INVISIBLE (-2350 2125);
FORCEPROP 1 LAST PATH I48
J 0
(-2677 2250);
DISPLAY 0.872340 (-2677 2250);
PAINT GREEN (-2677 2250);
DISPLAY INVISIBLE (-2677 2250);
FORCEADD TAP..1
(-2825 2550);
FORCEPROP 3 LASTPIN (-2875 2550) SIG_NAME P3E_CPU0_PE2_SS_TXP<7>
J 0
(-2865 2560);
DISPLAY 0.659574 (-2865 2560);
PAINT MONO (-2865 2560);
DISPLAY INVISIBLE (-2865 2560);
FORCEPROP 1 LASTPIN (-2875 2550) BN 7
J 0
(-2887 2558);
DISPLAY 0.617021 (-2887 2558);
PAINT PINK (-2887 2558);
FORCEPROP 2 LAST CDS_LIB mstr_standard
J 2
(-2825 2550);
PAINT MONO (-2825 2550);
DISPLAY INVISIBLE (-2825 2550);
FORCEPROP 1 LAST BODY_TYPE PLUMBING
J 0
(-2825 2600);
DISPLAY 1.446809 (-2825 2600);
PAINT GREEN (-2825 2600);
DISPLAY INVISIBLE (-2825 2600);
FORCEPROP 1 LAST HDL_TAP TRUE
J 0
(-2500 2425);
DISPLAY 1.446809 (-2500 2425);
PAINT GREEN (-2500 2425);
DISPLAY INVISIBLE (-2500 2425);
FORCEPROP 1 LAST PATH I49
J 0
(-2827 2550);
DISPLAY 0.872340 (-2827 2550);
PAINT GREEN (-2827 2550);
DISPLAY INVISIBLE (-2827 2550);
FORCEADD TAP..1
R 2
(-5300 1750);
FORCEPROP 3 LASTPIN (-5250 1750) SIG_NAME P3E_CPU0_PE2_SS_RXN<2>
J 0
(-5240 1760);
DISPLAY 0.659574 (-5240 1760);
PAINT MONO (-5240 1760);
DISPLAY INVISIBLE (-5240 1760);
FORCEPROP 1 LASTPIN (-5250 1750) BN 2
J 2
(-5238 1758);
DISPLAY 0.617021 (-5238 1758);
PAINT PINK (-5238 1758);
FORCEPROP 2 LAST CDS_LIB mstr_standard
J 0
(-5300 1750);
PAINT MONO (-5300 1750);
DISPLAY INVISIBLE (-5300 1750);
FORCEPROP 1 LAST BODY_TYPE PLUMBING
J 2
(-5300 1800);
DISPLAY 1.446809 (-5300 1800);
PAINT GREEN (-5300 1800);
DISPLAY INVISIBLE (-5300 1800);
FORCEPROP 1 LAST HDL_TAP TRUE
J 2
(-5625 1625);
DISPLAY 1.446809 (-5625 1625);
PAINT GREEN (-5625 1625);
DISPLAY INVISIBLE (-5625 1625);
FORCEPROP 1 LAST PATH I5
J 2
(-5298 1750);
DISPLAY 0.872340 (-5298 1750);
PAINT GREEN (-5298 1750);
DISPLAY INVISIBLE (-5298 1750);
FORCEADD TAP..1
(-2825 2450);
FORCEPROP 3 LASTPIN (-2875 2450) SIG_NAME P3E_CPU0_PE2_SS_TXP<5>
J 0
(-2865 2460);
DISPLAY 0.659574 (-2865 2460);
PAINT MONO (-2865 2460);
DISPLAY INVISIBLE (-2865 2460);
FORCEPROP 1 LASTPIN (-2875 2450) BN 5
J 0
(-2887 2458);
DISPLAY 0.617021 (-2887 2458);
PAINT PINK (-2887 2458);
FORCEPROP 2 LAST CDS_LIB mstr_standard
J 2
(-2825 2450);
PAINT MONO (-2825 2450);
DISPLAY INVISIBLE (-2825 2450);
FORCEPROP 1 LAST BODY_TYPE PLUMBING
J 0
(-2825 2500);
DISPLAY 1.446809 (-2825 2500);
PAINT GREEN (-2825 2500);
DISPLAY INVISIBLE (-2825 2500);
FORCEPROP 1 LAST HDL_TAP TRUE
J 0
(-2500 2325);
DISPLAY 1.446809 (-2500 2325);
PAINT GREEN (-2500 2325);
DISPLAY INVISIBLE (-2500 2325);
FORCEPROP 1 LAST PATH I50
J 0
(-2827 2450);
DISPLAY 0.872340 (-2827 2450);
PAINT GREEN (-2827 2450);
DISPLAY INVISIBLE (-2827 2450);
FORCEADD TAP..1
(-2825 2500);
FORCEPROP 3 LASTPIN (-2875 2500) SIG_NAME P3E_CPU0_PE2_SS_TXP<6>
J 0
(-2865 2510);
DISPLAY 0.659574 (-2865 2510);
PAINT MONO (-2865 2510);
DISPLAY INVISIBLE (-2865 2510);
FORCEPROP 1 LASTPIN (-2875 2500) BN 6
J 0
(-2887 2508);
DISPLAY 0.617021 (-2887 2508);
PAINT PINK (-2887 2508);
FORCEPROP 2 LAST CDS_LIB mstr_standard
J 2
(-2825 2500);
PAINT MONO (-2825 2500);
DISPLAY INVISIBLE (-2825 2500);
FORCEPROP 1 LAST BODY_TYPE PLUMBING
J 0
(-2825 2550);
DISPLAY 1.446809 (-2825 2550);
PAINT GREEN (-2825 2550);
DISPLAY INVISIBLE (-2825 2550);
FORCEPROP 1 LAST HDL_TAP TRUE
J 0
(-2500 2375);
DISPLAY 1.446809 (-2500 2375);
PAINT GREEN (-2500 2375);
DISPLAY INVISIBLE (-2500 2375);
FORCEPROP 1 LAST PATH I51
J 0
(-2827 2500);
DISPLAY 0.872340 (-2827 2500);
PAINT GREEN (-2827 2500);
DISPLAY INVISIBLE (-2827 2500);
FORCEADD TAP..1
R 2
(-5300 1800);
FORCEPROP 3 LASTPIN (-5250 1800) SIG_NAME P3E_CPU0_PE2_SS_RXN<3>
J 0
(-5240 1810);
DISPLAY 0.659574 (-5240 1810);
PAINT MONO (-5240 1810);
DISPLAY INVISIBLE (-5240 1810);
FORCEPROP 1 LASTPIN (-5250 1800) BN 3
J 2
(-5238 1808);
DISPLAY 0.617021 (-5238 1808);
PAINT PINK (-5238 1808);
FORCEPROP 2 LAST CDS_LIB mstr_standard
J 0
(-5300 1800);
PAINT MONO (-5300 1800);
DISPLAY INVISIBLE (-5300 1800);
FORCEPROP 1 LAST BODY_TYPE PLUMBING
J 2
(-5300 1850);
DISPLAY 1.446809 (-5300 1850);
PAINT GREEN (-5300 1850);
DISPLAY INVISIBLE (-5300 1850);
FORCEPROP 1 LAST HDL_TAP TRUE
J 2
(-5625 1675);
DISPLAY 1.446809 (-5625 1675);
PAINT GREEN (-5625 1675);
DISPLAY INVISIBLE (-5625 1675);
FORCEPROP 1 LAST PATH I6
J 2
(-5298 1800);
DISPLAY 0.872340 (-5298 1800);
PAINT GREEN (-5298 1800);
DISPLAY INVISIBLE (-5298 1800);
FORCEADD TAP..1
R 2
(-5450 1900);
FORCEPROP 3 LASTPIN (-5400 1900) SIG_NAME P3E_CPU0_PE2_SS_RXP<0>
J 0
(-5390 1910);
DISPLAY 0.659574 (-5390 1910);
PAINT MONO (-5390 1910);
DISPLAY INVISIBLE (-5390 1910);
FORCEPROP 1 LASTPIN (-5400 1900) BN 0
J 2
(-5388 1908);
DISPLAY 0.617021 (-5388 1908);
PAINT PINK (-5388 1908);
FORCEPROP 2 LAST CDS_LIB mstr_standard
J 0
(-5450 1900);
PAINT MONO (-5450 1900);
DISPLAY INVISIBLE (-5450 1900);
FORCEPROP 1 LAST BODY_TYPE PLUMBING
J 2
(-5450 1950);
DISPLAY 1.446809 (-5450 1950);
PAINT GREEN (-5450 1950);
DISPLAY INVISIBLE (-5450 1950);
FORCEPROP 1 LAST HDL_TAP TRUE
J 2
(-5775 1775);
DISPLAY 1.446809 (-5775 1775);
PAINT GREEN (-5775 1775);
DISPLAY INVISIBLE (-5775 1775);
FORCEPROP 1 LAST PATH I7
J 2
(-5448 1900);
DISPLAY 0.872340 (-5448 1900);
PAINT GREEN (-5448 1900);
DISPLAY INVISIBLE (-5448 1900);
FORCEADD OFFPAGE..2
(-1725 3625);
FORCEPROP 2 LAST $XR0 105 
J 0
(-1536 3625);
DISPLAY 0.638298 (-1536 3625);
PAINT MONO (-1536 3625);
FORCEPROP 2 LAST CDS_LIB mstr_standard
J 0
(-1725 3625);
PAINT MONO (-1725 3625);
DISPLAY INVISIBLE (-1725 3625);
FORCEPROP 1 LAST OFFPAGE TRUE
J 0
(-1400 3500);
DISPLAY 1.170213 (-1400 3500);
PAINT GREEN (-1400 3500);
DISPLAY INVISIBLE (-1400 3500);
FORCEPROP 1 LAST COMMENT_BODY TRUE
J 0
(-1770 3530);
DISPLAY 1.170213 (-1770 3530);
PAINT GREEN (-1770 3530);
DISPLAY INVISIBLE (-1770 3530);
FORCEPROP 2 LAST PATH I70
J 0
(-1400 3675);
DISPLAY 1.021277 (-1400 3675);
PAINT ORANGE (-1400 3675);
DISPLAY INVISIBLE (-1400 3675);
FORCEADD OFFPAGE..2
(-1725 3575);
FORCEPROP 2 LAST $XR0 105 
J 0
(-1536 3575);
DISPLAY 0.638298 (-1536 3575);
PAINT MONO (-1536 3575);
FORCEPROP 2 LAST CDS_LIB mstr_standard
J 0
(-1725 3575);
PAINT MONO (-1725 3575);
DISPLAY INVISIBLE (-1725 3575);
FORCEPROP 1 LAST OFFPAGE TRUE
J 0
(-1400 3450);
DISPLAY 1.170213 (-1400 3450);
PAINT GREEN (-1400 3450);
DISPLAY INVISIBLE (-1400 3450);
FORCEPROP 1 LAST COMMENT_BODY TRUE
J 0
(-1770 3480);
DISPLAY 1.170213 (-1770 3480);
PAINT GREEN (-1770 3480);
DISPLAY INVISIBLE (-1770 3480);
FORCEPROP 2 LAST PATH I71
J 0
(-1400 3625);
DISPLAY 1.021277 (-1400 3625);
PAINT ORANGE (-1400 3625);
DISPLAY INVISIBLE (-1400 3625);
FORCEADD TAP..1
(-2675 3200);
FORCEPROP 3 LASTPIN (-2725 3200) SIG_NAME P3E_CPU0_PE2_SS_TXN<13>
J 0
(-2715 3210);
DISPLAY 0.659574 (-2715 3210);
PAINT MONO (-2715 3210);
DISPLAY INVISIBLE (-2715 3210);
FORCEPROP 1 LASTPIN (-2725 3200) BN 13
J 0
(-2737 3208);
DISPLAY 0.617021 (-2737 3208);
PAINT PINK (-2737 3208);
FORCEPROP 2 LAST CDS_LIB mstr_standard
J 2
(-2675 3200);
PAINT MONO (-2675 3200);
DISPLAY INVISIBLE (-2675 3200);
FORCEPROP 1 LAST BODY_TYPE PLUMBING
J 0
(-2675 3250);
DISPLAY 1.446809 (-2675 3250);
PAINT GREEN (-2675 3250);
DISPLAY INVISIBLE (-2675 3250);
FORCEPROP 1 LAST HDL_TAP TRUE
J 0
(-2350 3075);
DISPLAY 1.446809 (-2350 3075);
PAINT GREEN (-2350 3075);
DISPLAY INVISIBLE (-2350 3075);
FORCEPROP 1 LAST PATH I72
J 0
(-2677 3200);
DISPLAY 0.872340 (-2677 3200);
PAINT GREEN (-2677 3200);
DISPLAY INVISIBLE (-2677 3200);
FORCEADD TAP..1
(-2675 3300);
FORCEPROP 3 LASTPIN (-2725 3300) SIG_NAME P3E_CPU0_PE2_SS_TXN<15>
J 0
(-2715 3310);
DISPLAY 0.659574 (-2715 3310);
PAINT MONO (-2715 3310);
DISPLAY INVISIBLE (-2715 3310);
FORCEPROP 1 LASTPIN (-2725 3300) BN 15
J 0
(-2737 3308);
DISPLAY 0.617021 (-2737 3308);
PAINT PINK (-2737 3308);
FORCEPROP 2 LAST CDS_LIB mstr_standard
J 2
(-2675 3300);
PAINT MONO (-2675 3300);
DISPLAY INVISIBLE (-2675 3300);
FORCEPROP 1 LAST BODY_TYPE PLUMBING
J 0
(-2675 3350);
DISPLAY 1.446809 (-2675 3350);
PAINT GREEN (-2675 3350);
DISPLAY INVISIBLE (-2675 3350);
FORCEPROP 1 LAST HDL_TAP TRUE
J 0
(-2350 3175);
DISPLAY 1.446809 (-2350 3175);
PAINT GREEN (-2350 3175);
DISPLAY INVISIBLE (-2350 3175);
FORCEPROP 1 LAST PATH I73
J 0
(-2677 3300);
DISPLAY 0.872340 (-2677 3300);
PAINT GREEN (-2677 3300);
DISPLAY INVISIBLE (-2677 3300);
FORCEADD TAP..1
(-2675 3250);
FORCEPROP 3 LASTPIN (-2725 3250) SIG_NAME P3E_CPU0_PE2_SS_TXN<14>
J 0
(-2715 3260);
DISPLAY 0.659574 (-2715 3260);
PAINT MONO (-2715 3260);
DISPLAY INVISIBLE (-2715 3260);
FORCEPROP 1 LASTPIN (-2725 3250) BN 14
J 0
(-2737 3258);
DISPLAY 0.617021 (-2737 3258);
PAINT PINK (-2737 3258);
FORCEPROP 2 LAST CDS_LIB mstr_standard
J 2
(-2675 3250);
PAINT MONO (-2675 3250);
DISPLAY INVISIBLE (-2675 3250);
FORCEPROP 1 LAST BODY_TYPE PLUMBING
J 0
(-2675 3300);
DISPLAY 1.446809 (-2675 3300);
PAINT GREEN (-2675 3300);
DISPLAY INVISIBLE (-2675 3300);
FORCEPROP 1 LAST HDL_TAP TRUE
J 0
(-2350 3125);
DISPLAY 1.446809 (-2350 3125);
PAINT GREEN (-2350 3125);
DISPLAY INVISIBLE (-2350 3125);
FORCEPROP 1 LAST PATH I74
J 0
(-2677 3250);
DISPLAY 0.872340 (-2677 3250);
PAINT GREEN (-2677 3250);
DISPLAY INVISIBLE (-2677 3250);
FORCEADD TAP..1
(-2675 3150);
FORCEPROP 3 LASTPIN (-2725 3150) SIG_NAME P3E_CPU0_PE2_SS_TXN<12>
J 0
(-2715 3160);
DISPLAY 0.659574 (-2715 3160);
PAINT MONO (-2715 3160);
DISPLAY INVISIBLE (-2715 3160);
FORCEPROP 1 LASTPIN (-2725 3150) BN 12
J 0
(-2737 3158);
DISPLAY 0.617021 (-2737 3158);
PAINT PINK (-2737 3158);
FORCEPROP 2 LAST CDS_LIB mstr_standard
J 2
(-2675 3150);
PAINT MONO (-2675 3150);
DISPLAY INVISIBLE (-2675 3150);
FORCEPROP 1 LAST BODY_TYPE PLUMBING
J 0
(-2675 3200);
DISPLAY 1.446809 (-2675 3200);
PAINT GREEN (-2675 3200);
DISPLAY INVISIBLE (-2675 3200);
FORCEPROP 1 LAST HDL_TAP TRUE
J 0
(-2350 3025);
DISPLAY 1.446809 (-2350 3025);
PAINT GREEN (-2350 3025);
DISPLAY INVISIBLE (-2350 3025);
FORCEPROP 1 LAST PATH I75
J 0
(-2677 3150);
DISPLAY 0.872340 (-2677 3150);
PAINT GREEN (-2677 3150);
DISPLAY INVISIBLE (-2677 3150);
FORCEADD TAP..1
(-2825 3500);
FORCEPROP 3 LASTPIN (-2875 3500) SIG_NAME P3E_CPU0_PE2_SS_TXP<14>
J 0
(-2865 3510);
DISPLAY 0.659574 (-2865 3510);
PAINT MONO (-2865 3510);
DISPLAY INVISIBLE (-2865 3510);
FORCEPROP 1 LASTPIN (-2875 3500) BN 14
J 0
(-2887 3508);
DISPLAY 0.617021 (-2887 3508);
PAINT PINK (-2887 3508);
FORCEPROP 2 LAST CDS_LIB mstr_standard
J 2
(-2825 3500);
PAINT MONO (-2825 3500);
DISPLAY INVISIBLE (-2825 3500);
FORCEPROP 1 LAST BODY_TYPE PLUMBING
J 0
(-2825 3550);
DISPLAY 1.446809 (-2825 3550);
PAINT GREEN (-2825 3550);
DISPLAY INVISIBLE (-2825 3550);
FORCEPROP 1 LAST HDL_TAP TRUE
J 0
(-2500 3375);
DISPLAY 1.446809 (-2500 3375);
PAINT GREEN (-2500 3375);
DISPLAY INVISIBLE (-2500 3375);
FORCEPROP 1 LAST PATH I76
J 0
(-2827 3500);
DISPLAY 0.872340 (-2827 3500);
PAINT GREEN (-2827 3500);
DISPLAY INVISIBLE (-2827 3500);
FORCEADD TAP..1
(-2825 3550);
FORCEPROP 3 LASTPIN (-2875 3550) SIG_NAME P3E_CPU0_PE2_SS_TXP<15>
J 0
(-2865 3560);
DISPLAY 0.659574 (-2865 3560);
PAINT MONO (-2865 3560);
DISPLAY INVISIBLE (-2865 3560);
FORCEPROP 1 LASTPIN (-2875 3550) BN 15
J 0
(-2887 3558);
DISPLAY 0.617021 (-2887 3558);
PAINT PINK (-2887 3558);
FORCEPROP 2 LAST CDS_LIB mstr_standard
J 2
(-2825 3550);
PAINT MONO (-2825 3550);
DISPLAY INVISIBLE (-2825 3550);
FORCEPROP 1 LAST BODY_TYPE PLUMBING
J 0
(-2825 3600);
DISPLAY 1.446809 (-2825 3600);
PAINT GREEN (-2825 3600);
DISPLAY INVISIBLE (-2825 3600);
FORCEPROP 1 LAST HDL_TAP TRUE
J 0
(-2500 3425);
DISPLAY 1.446809 (-2500 3425);
PAINT GREEN (-2500 3425);
DISPLAY INVISIBLE (-2500 3425);
FORCEPROP 1 LAST PATH I77
J 0
(-2827 3550);
DISPLAY 0.872340 (-2827 3550);
PAINT GREEN (-2827 3550);
DISPLAY INVISIBLE (-2827 3550);
FORCEADD TAP..1
(-2825 3450);
FORCEPROP 3 LASTPIN (-2875 3450) SIG_NAME P3E_CPU0_PE2_SS_TXP<13>
J 0
(-2865 3460);
DISPLAY 0.659574 (-2865 3460);
PAINT MONO (-2865 3460);
DISPLAY INVISIBLE (-2865 3460);
FORCEPROP 1 LASTPIN (-2875 3450) BN 13
J 0
(-2887 3458);
DISPLAY 0.617021 (-2887 3458);
PAINT PINK (-2887 3458);
FORCEPROP 2 LAST CDS_LIB mstr_standard
J 2
(-2825 3450);
PAINT MONO (-2825 3450);
DISPLAY INVISIBLE (-2825 3450);
FORCEPROP 1 LAST BODY_TYPE PLUMBING
J 0
(-2825 3500);
DISPLAY 1.446809 (-2825 3500);
PAINT GREEN (-2825 3500);
DISPLAY INVISIBLE (-2825 3500);
FORCEPROP 1 LAST HDL_TAP TRUE
J 0
(-2500 3325);
DISPLAY 1.446809 (-2500 3325);
PAINT GREEN (-2500 3325);
DISPLAY INVISIBLE (-2500 3325);
FORCEPROP 1 LAST PATH I78
J 0
(-2827 3450);
DISPLAY 0.872340 (-2827 3450);
PAINT GREEN (-2827 3450);
DISPLAY INVISIBLE (-2827 3450);
FORCEADD TAP..1
(-2825 3400);
FORCEPROP 3 LASTPIN (-2875 3400) SIG_NAME P3E_CPU0_PE2_SS_TXP<12>
J 0
(-2865 3410);
DISPLAY 0.659574 (-2865 3410);
PAINT MONO (-2865 3410);
DISPLAY INVISIBLE (-2865 3410);
FORCEPROP 1 LASTPIN (-2875 3400) BN 12
J 0
(-2887 3408);
DISPLAY 0.617021 (-2887 3408);
PAINT PINK (-2887 3408);
FORCEPROP 2 LAST CDS_LIB mstr_standard
J 2
(-2825 3400);
PAINT MONO (-2825 3400);
DISPLAY INVISIBLE (-2825 3400);
FORCEPROP 1 LAST BODY_TYPE PLUMBING
J 0
(-2825 3450);
DISPLAY 1.446809 (-2825 3450);
PAINT GREEN (-2825 3450);
DISPLAY INVISIBLE (-2825 3450);
FORCEPROP 1 LAST HDL_TAP TRUE
J 0
(-2500 3275);
DISPLAY 1.446809 (-2500 3275);
PAINT GREEN (-2500 3275);
DISPLAY INVISIBLE (-2500 3275);
FORCEPROP 1 LAST PATH I79
J 0
(-2827 3400);
DISPLAY 0.872340 (-2827 3400);
PAINT GREEN (-2827 3400);
DISPLAY INVISIBLE (-2827 3400);
FORCEADD TAP..1
(-2825 3050);
FORCEPROP 3 LASTPIN (-2875 3050) SIG_NAME P3E_CPU0_PE2_SS_TXP<11>
J 0
(-2865 3060);
DISPLAY 0.659574 (-2865 3060);
PAINT MONO (-2865 3060);
DISPLAY INVISIBLE (-2865 3060);
FORCEPROP 1 LASTPIN (-2875 3050) BN 11
J 0
(-2862 3058);
DISPLAY 0.617021 (-2862 3058);
PAINT PINK (-2862 3058);
FORCEPROP 2 LAST CDS_LIB mstr_standard
J 2
(-2825 3050);
PAINT MONO (-2825 3050);
DISPLAY INVISIBLE (-2825 3050);
FORCEPROP 1 LAST BODY_TYPE PLUMBING
J 0
(-2825 3100);
DISPLAY 1.446809 (-2825 3100);
PAINT GREEN (-2825 3100);
DISPLAY INVISIBLE (-2825 3100);
FORCEPROP 1 LAST HDL_TAP TRUE
J 0
(-2500 2925);
DISPLAY 1.446809 (-2500 2925);
PAINT GREEN (-2500 2925);
DISPLAY INVISIBLE (-2500 2925);
FORCEPROP 1 LAST PATH I80
J 0
(-2827 3050);
DISPLAY 0.872340 (-2827 3050);
PAINT GREEN (-2827 3050);
DISPLAY INVISIBLE (-2827 3050);
FORCEADD TAP..1
(-2675 2800);
FORCEPROP 3 LASTPIN (-2725 2800) SIG_NAME P3E_CPU0_PE2_SS_TXN<11>
J 0
(-2715 2810);
DISPLAY 0.659574 (-2715 2810);
PAINT MONO (-2715 2810);
DISPLAY INVISIBLE (-2715 2810);
FORCEPROP 1 LASTPIN (-2725 2800) BN 11
J 0
(-2737 2808);
DISPLAY 0.617021 (-2737 2808);
PAINT PINK (-2737 2808);
FORCEPROP 2 LAST CDS_LIB mstr_standard
J 2
(-2675 2800);
PAINT MONO (-2675 2800);
DISPLAY INVISIBLE (-2675 2800);
FORCEPROP 1 LAST BODY_TYPE PLUMBING
J 0
(-2675 2850);
DISPLAY 1.446809 (-2675 2850);
PAINT GREEN (-2675 2850);
DISPLAY INVISIBLE (-2675 2850);
FORCEPROP 1 LAST HDL_TAP TRUE
J 0
(-2350 2675);
DISPLAY 1.446809 (-2350 2675);
PAINT GREEN (-2350 2675);
DISPLAY INVISIBLE (-2350 2675);
FORCEPROP 1 LAST PATH I81
J 0
(-2677 2800);
DISPLAY 0.872340 (-2677 2800);
PAINT GREEN (-2677 2800);
DISPLAY INVISIBLE (-2677 2800);
FORCEADD TAP..1
(-2675 2750);
FORCEPROP 3 LASTPIN (-2725 2750) SIG_NAME P3E_CPU0_PE2_SS_TXN<10>
J 0
(-2715 2760);
DISPLAY 0.659574 (-2715 2760);
PAINT MONO (-2715 2760);
DISPLAY INVISIBLE (-2715 2760);
FORCEPROP 1 LASTPIN (-2725 2750) BN 10
J 0
(-2737 2758);
DISPLAY 0.617021 (-2737 2758);
PAINT PINK (-2737 2758);
FORCEPROP 2 LAST CDS_LIB mstr_standard
J 2
(-2675 2750);
PAINT MONO (-2675 2750);
DISPLAY INVISIBLE (-2675 2750);
FORCEPROP 1 LAST BODY_TYPE PLUMBING
J 0
(-2675 2800);
DISPLAY 1.446809 (-2675 2800);
PAINT GREEN (-2675 2800);
DISPLAY INVISIBLE (-2675 2800);
FORCEPROP 1 LAST HDL_TAP TRUE
J 0
(-2350 2625);
DISPLAY 1.446809 (-2350 2625);
PAINT GREEN (-2350 2625);
DISPLAY INVISIBLE (-2350 2625);
FORCEPROP 1 LAST PATH I82
J 0
(-2677 2750);
DISPLAY 0.872340 (-2677 2750);
PAINT GREEN (-2677 2750);
DISPLAY INVISIBLE (-2677 2750);
FORCEADD TAP..1
(-2675 2700);
FORCEPROP 3 LASTPIN (-2725 2700) SIG_NAME P3E_CPU0_PE2_SS_TXN<9>
J 0
(-2715 2710);
DISPLAY 0.659574 (-2715 2710);
PAINT MONO (-2715 2710);
DISPLAY INVISIBLE (-2715 2710);
FORCEPROP 1 LASTPIN (-2725 2700) BN 9
J 0
(-2737 2708);
DISPLAY 0.617021 (-2737 2708);
PAINT PINK (-2737 2708);
FORCEPROP 2 LAST CDS_LIB mstr_standard
J 2
(-2675 2700);
PAINT MONO (-2675 2700);
DISPLAY INVISIBLE (-2675 2700);
FORCEPROP 1 LAST BODY_TYPE PLUMBING
J 0
(-2675 2750);
DISPLAY 1.446809 (-2675 2750);
PAINT GREEN (-2675 2750);
DISPLAY INVISIBLE (-2675 2750);
FORCEPROP 1 LAST HDL_TAP TRUE
J 0
(-2350 2575);
DISPLAY 1.446809 (-2350 2575);
PAINT GREEN (-2350 2575);
DISPLAY INVISIBLE (-2350 2575);
FORCEPROP 1 LAST PATH I83
J 0
(-2677 2700);
DISPLAY 0.872340 (-2677 2700);
PAINT GREEN (-2677 2700);
DISPLAY INVISIBLE (-2677 2700);
FORCEADD TAP..1
(-2675 2650);
FORCEPROP 3 LASTPIN (-2725 2650) SIG_NAME P3E_CPU0_PE2_SS_TXN<8>
J 0
(-2715 2660);
DISPLAY 0.659574 (-2715 2660);
PAINT MONO (-2715 2660);
DISPLAY INVISIBLE (-2715 2660);
FORCEPROP 1 LASTPIN (-2725 2650) BN 8
J 0
(-2737 2658);
DISPLAY 0.617021 (-2737 2658);
PAINT PINK (-2737 2658);
FORCEPROP 2 LAST CDS_LIB mstr_standard
J 2
(-2675 2650);
PAINT MONO (-2675 2650);
DISPLAY INVISIBLE (-2675 2650);
FORCEPROP 1 LAST BODY_TYPE PLUMBING
J 0
(-2675 2700);
DISPLAY 1.446809 (-2675 2700);
PAINT GREEN (-2675 2700);
DISPLAY INVISIBLE (-2675 2700);
FORCEPROP 1 LAST HDL_TAP TRUE
J 0
(-2350 2525);
DISPLAY 1.446809 (-2350 2525);
PAINT GREEN (-2350 2525);
DISPLAY INVISIBLE (-2350 2525);
FORCEPROP 1 LAST PATH I84
J 0
(-2677 2650);
DISPLAY 0.872340 (-2677 2650);
PAINT GREEN (-2677 2650);
DISPLAY INVISIBLE (-2677 2650);
FORCEADD TAP..1
(-2825 3000);
FORCEPROP 3 LASTPIN (-2875 3000) SIG_NAME P3E_CPU0_PE2_SS_TXP<10>
J 0
(-2865 3010);
DISPLAY 0.659574 (-2865 3010);
PAINT MONO (-2865 3010);
DISPLAY INVISIBLE (-2865 3010);
FORCEPROP 1 LASTPIN (-2875 3000) BN 10
J 0
(-2887 3008);
DISPLAY 0.617021 (-2887 3008);
PAINT PINK (-2887 3008);
FORCEPROP 2 LAST CDS_LIB mstr_standard
J 2
(-2825 3000);
PAINT MONO (-2825 3000);
DISPLAY INVISIBLE (-2825 3000);
FORCEPROP 1 LAST BODY_TYPE PLUMBING
J 0
(-2825 3050);
DISPLAY 1.446809 (-2825 3050);
PAINT GREEN (-2825 3050);
DISPLAY INVISIBLE (-2825 3050);
FORCEPROP 1 LAST HDL_TAP TRUE
J 0
(-2500 2875);
DISPLAY 1.446809 (-2500 2875);
PAINT GREEN (-2500 2875);
DISPLAY INVISIBLE (-2500 2875);
FORCEPROP 1 LAST PATH I85
J 0
(-2827 3000);
DISPLAY 0.872340 (-2827 3000);
PAINT GREEN (-2827 3000);
DISPLAY INVISIBLE (-2827 3000);
FORCEADD TAP..1
(-2825 2950);
FORCEPROP 3 LASTPIN (-2875 2950) SIG_NAME P3E_CPU0_PE2_SS_TXP<9>
J 0
(-2865 2960);
DISPLAY 0.659574 (-2865 2960);
PAINT MONO (-2865 2960);
DISPLAY INVISIBLE (-2865 2960);
FORCEPROP 1 LASTPIN (-2875 2950) BN 9
J 0
(-2887 2958);
DISPLAY 0.617021 (-2887 2958);
PAINT PINK (-2887 2958);
FORCEPROP 2 LAST CDS_LIB mstr_standard
J 2
(-2825 2950);
PAINT MONO (-2825 2950);
DISPLAY INVISIBLE (-2825 2950);
FORCEPROP 1 LAST BODY_TYPE PLUMBING
J 0
(-2825 3000);
DISPLAY 1.446809 (-2825 3000);
PAINT GREEN (-2825 3000);
DISPLAY INVISIBLE (-2825 3000);
FORCEPROP 1 LAST HDL_TAP TRUE
J 0
(-2500 2825);
DISPLAY 1.446809 (-2500 2825);
PAINT GREEN (-2500 2825);
DISPLAY INVISIBLE (-2500 2825);
FORCEPROP 1 LAST PATH I86
J 0
(-2827 2950);
DISPLAY 0.872340 (-2827 2950);
PAINT GREEN (-2827 2950);
DISPLAY INVISIBLE (-2827 2950);
FORCEADD TAP..1
(-2825 2900);
FORCEPROP 3 LASTPIN (-2875 2900) SIG_NAME P3E_CPU0_PE2_SS_TXP<8>
J 0
(-2865 2910);
DISPLAY 0.659574 (-2865 2910);
PAINT MONO (-2865 2910);
DISPLAY INVISIBLE (-2865 2910);
FORCEPROP 1 LASTPIN (-2875 2900) BN 8
J 0
(-2887 2908);
DISPLAY 0.617021 (-2887 2908);
PAINT PINK (-2887 2908);
FORCEPROP 2 LAST CDS_LIB mstr_standard
J 2
(-2825 2900);
PAINT MONO (-2825 2900);
DISPLAY INVISIBLE (-2825 2900);
FORCEPROP 1 LAST BODY_TYPE PLUMBING
J 0
(-2825 2950);
DISPLAY 1.446809 (-2825 2950);
PAINT GREEN (-2825 2950);
DISPLAY INVISIBLE (-2825 2950);
FORCEPROP 1 LAST HDL_TAP TRUE
J 0
(-2500 2775);
DISPLAY 1.446809 (-2500 2775);
PAINT GREEN (-2500 2775);
DISPLAY INVISIBLE (-2500 2775);
FORCEPROP 1 LAST PATH I87
J 0
(-2827 2900);
DISPLAY 0.872340 (-2827 2900);
PAINT GREEN (-2827 2900);
DISPLAY INVISIBLE (-2827 2900);
FORCEADD TAP..1
R 2
(-5300 3300);
FORCEPROP 3 LASTPIN (-5250 3300) SIG_NAME P3E_CPU0_PE2_SS_RXN<15>
J 0
(-5240 3310);
DISPLAY 0.659574 (-5240 3310);
PAINT MONO (-5240 3310);
DISPLAY INVISIBLE (-5240 3310);
FORCEPROP 1 LASTPIN (-5250 3300) BN 15
J 2
(-5238 3308);
DISPLAY 0.617021 (-5238 3308);
PAINT PINK (-5238 3308);
FORCEPROP 2 LAST CDS_LIB mstr_standard
J 0
(-5300 3300);
PAINT MONO (-5300 3300);
DISPLAY INVISIBLE (-5300 3300);
FORCEPROP 1 LAST BODY_TYPE PLUMBING
J 2
(-5300 3350);
DISPLAY 1.446809 (-5300 3350);
PAINT GREEN (-5300 3350);
DISPLAY INVISIBLE (-5300 3350);
FORCEPROP 1 LAST HDL_TAP TRUE
J 2
(-5625 3175);
DISPLAY 1.446809 (-5625 3175);
PAINT GREEN (-5625 3175);
DISPLAY INVISIBLE (-5625 3175);
FORCEPROP 1 LAST PATH I88
J 2
(-5298 3300);
DISPLAY 0.872340 (-5298 3300);
PAINT GREEN (-5298 3300);
DISPLAY INVISIBLE (-5298 3300);
FORCEADD TAP..1
R 2
(-5300 3250);
FORCEPROP 3 LASTPIN (-5250 3250) SIG_NAME P3E_CPU0_PE2_SS_RXN<14>
J 0
(-5240 3260);
DISPLAY 0.659574 (-5240 3260);
PAINT MONO (-5240 3260);
DISPLAY INVISIBLE (-5240 3260);
FORCEPROP 1 LASTPIN (-5250 3250) BN 14
J 2
(-5238 3258);
DISPLAY 0.617021 (-5238 3258);
PAINT PINK (-5238 3258);
FORCEPROP 2 LAST CDS_LIB mstr_standard
J 0
(-5300 3250);
PAINT MONO (-5300 3250);
DISPLAY INVISIBLE (-5300 3250);
FORCEPROP 1 LAST BODY_TYPE PLUMBING
J 2
(-5300 3300);
DISPLAY 1.446809 (-5300 3300);
PAINT GREEN (-5300 3300);
DISPLAY INVISIBLE (-5300 3300);
FORCEPROP 1 LAST HDL_TAP TRUE
J 2
(-5625 3125);
DISPLAY 1.446809 (-5625 3125);
PAINT GREEN (-5625 3125);
DISPLAY INVISIBLE (-5625 3125);
FORCEPROP 1 LAST PATH I89
J 2
(-5298 3250);
DISPLAY 0.872340 (-5298 3250);
PAINT GREEN (-5298 3250);
DISPLAY INVISIBLE (-5298 3250);
FORCEADD TAP..1
R 2
(-5450 2050);
FORCEPROP 3 LASTPIN (-5400 2050) SIG_NAME P3E_CPU0_PE2_SS_RXP<3>
J 0
(-5390 2060);
DISPLAY 0.659574 (-5390 2060);
PAINT MONO (-5390 2060);
DISPLAY INVISIBLE (-5390 2060);
FORCEPROP 1 LASTPIN (-5400 2050) BN 3
J 2
(-5388 2058);
DISPLAY 0.617021 (-5388 2058);
PAINT PINK (-5388 2058);
FORCEPROP 2 LAST CDS_LIB mstr_standard
J 0
(-5450 2050);
PAINT MONO (-5450 2050);
DISPLAY INVISIBLE (-5450 2050);
FORCEPROP 1 LAST BODY_TYPE PLUMBING
J 2
(-5450 2100);
DISPLAY 1.446809 (-5450 2100);
PAINT GREEN (-5450 2100);
DISPLAY INVISIBLE (-5450 2100);
FORCEPROP 1 LAST HDL_TAP TRUE
J 2
(-5775 1925);
DISPLAY 1.446809 (-5775 1925);
PAINT GREEN (-5775 1925);
DISPLAY INVISIBLE (-5775 1925);
FORCEPROP 1 LAST PATH I9
J 2
(-5448 2050);
DISPLAY 0.872340 (-5448 2050);
PAINT GREEN (-5448 2050);
DISPLAY INVISIBLE (-5448 2050);
FORCEADD TAP..1
R 2
(-5300 3200);
FORCEPROP 3 LASTPIN (-5250 3200) SIG_NAME P3E_CPU0_PE2_SS_RXN<13>
J 0
(-5240 3210);
DISPLAY 0.659574 (-5240 3210);
PAINT MONO (-5240 3210);
DISPLAY INVISIBLE (-5240 3210);
FORCEPROP 1 LASTPIN (-5250 3200) BN 13
J 2
(-5238 3208);
DISPLAY 0.617021 (-5238 3208);
PAINT PINK (-5238 3208);
FORCEPROP 2 LAST CDS_LIB mstr_standard
J 0
(-5300 3200);
PAINT MONO (-5300 3200);
DISPLAY INVISIBLE (-5300 3200);
FORCEPROP 1 LAST BODY_TYPE PLUMBING
J 2
(-5300 3250);
DISPLAY 1.446809 (-5300 3250);
PAINT GREEN (-5300 3250);
DISPLAY INVISIBLE (-5300 3250);
FORCEPROP 1 LAST HDL_TAP TRUE
J 2
(-5625 3075);
DISPLAY 1.446809 (-5625 3075);
PAINT GREEN (-5625 3075);
DISPLAY INVISIBLE (-5625 3075);
FORCEPROP 1 LAST PATH I90
J 2
(-5298 3200);
DISPLAY 0.872340 (-5298 3200);
PAINT GREEN (-5298 3200);
DISPLAY INVISIBLE (-5298 3200);
FORCEADD TAP..1
R 2
(-5300 3150);
FORCEPROP 3 LASTPIN (-5250 3150) SIG_NAME P3E_CPU0_PE2_SS_RXN<12>
J 0
(-5240 3160);
DISPLAY 0.659574 (-5240 3160);
PAINT MONO (-5240 3160);
DISPLAY INVISIBLE (-5240 3160);
FORCEPROP 1 LASTPIN (-5250 3150) BN 12
J 2
(-5238 3158);
DISPLAY 0.617021 (-5238 3158);
PAINT PINK (-5238 3158);
FORCEPROP 2 LAST CDS_LIB mstr_standard
J 0
(-5300 3150);
PAINT MONO (-5300 3150);
DISPLAY INVISIBLE (-5300 3150);
FORCEPROP 1 LAST BODY_TYPE PLUMBING
J 2
(-5300 3200);
DISPLAY 1.446809 (-5300 3200);
PAINT GREEN (-5300 3200);
DISPLAY INVISIBLE (-5300 3200);
FORCEPROP 1 LAST HDL_TAP TRUE
J 2
(-5625 3025);
DISPLAY 1.446809 (-5625 3025);
PAINT GREEN (-5625 3025);
DISPLAY INVISIBLE (-5625 3025);
FORCEPROP 1 LAST PATH I91
J 2
(-5298 3150);
DISPLAY 0.872340 (-5298 3150);
PAINT GREEN (-5298 3150);
DISPLAY INVISIBLE (-5298 3150);
FORCEADD TAP..1
R 2
(-5450 3550);
FORCEPROP 3 LASTPIN (-5400 3550) SIG_NAME P3E_CPU0_PE2_SS_RXP<15>
J 0
(-5390 3560);
DISPLAY 0.659574 (-5390 3560);
PAINT MONO (-5390 3560);
DISPLAY INVISIBLE (-5390 3560);
FORCEPROP 1 LASTPIN (-5400 3550) BN 15
J 2
(-5388 3558);
DISPLAY 0.617021 (-5388 3558);
PAINT PINK (-5388 3558);
FORCEPROP 2 LAST CDS_LIB mstr_standard
J 0
(-5450 3550);
PAINT MONO (-5450 3550);
DISPLAY INVISIBLE (-5450 3550);
FORCEPROP 1 LAST BODY_TYPE PLUMBING
J 2
(-5450 3600);
DISPLAY 1.446809 (-5450 3600);
PAINT GREEN (-5450 3600);
DISPLAY INVISIBLE (-5450 3600);
FORCEPROP 1 LAST HDL_TAP TRUE
J 2
(-5775 3425);
DISPLAY 1.446809 (-5775 3425);
PAINT GREEN (-5775 3425);
DISPLAY INVISIBLE (-5775 3425);
FORCEPROP 1 LAST PATH I92
J 2
(-5448 3550);
DISPLAY 0.872340 (-5448 3550);
PAINT GREEN (-5448 3550);
DISPLAY INVISIBLE (-5448 3550);
FORCEADD TAP..1
R 2
(-5450 3500);
FORCEPROP 3 LASTPIN (-5400 3500) SIG_NAME P3E_CPU0_PE2_SS_RXP<14>
J 0
(-5390 3510);
DISPLAY 0.659574 (-5390 3510);
PAINT MONO (-5390 3510);
DISPLAY INVISIBLE (-5390 3510);
FORCEPROP 1 LASTPIN (-5400 3500) BN 14
J 2
(-5388 3508);
DISPLAY 0.617021 (-5388 3508);
PAINT PINK (-5388 3508);
FORCEPROP 2 LAST CDS_LIB mstr_standard
J 0
(-5450 3500);
PAINT MONO (-5450 3500);
DISPLAY INVISIBLE (-5450 3500);
FORCEPROP 1 LAST BODY_TYPE PLUMBING
J 2
(-5450 3550);
DISPLAY 1.446809 (-5450 3550);
PAINT GREEN (-5450 3550);
DISPLAY INVISIBLE (-5450 3550);
FORCEPROP 1 LAST HDL_TAP TRUE
J 2
(-5775 3375);
DISPLAY 1.446809 (-5775 3375);
PAINT GREEN (-5775 3375);
DISPLAY INVISIBLE (-5775 3375);
FORCEPROP 1 LAST PATH I93
J 2
(-5448 3500);
DISPLAY 0.872340 (-5448 3500);
PAINT GREEN (-5448 3500);
DISPLAY INVISIBLE (-5448 3500);
FORCEADD TAP..1
R 2
(-5450 3450);
FORCEPROP 3 LASTPIN (-5400 3450) SIG_NAME P3E_CPU0_PE2_SS_RXP<13>
J 0
(-5390 3460);
DISPLAY 0.659574 (-5390 3460);
PAINT MONO (-5390 3460);
DISPLAY INVISIBLE (-5390 3460);
FORCEPROP 1 LASTPIN (-5400 3450) BN 13
J 2
(-5388 3458);
DISPLAY 0.617021 (-5388 3458);
PAINT PINK (-5388 3458);
FORCEPROP 2 LAST CDS_LIB mstr_standard
J 0
(-5450 3450);
PAINT MONO (-5450 3450);
DISPLAY INVISIBLE (-5450 3450);
FORCEPROP 1 LAST BODY_TYPE PLUMBING
J 2
(-5450 3500);
DISPLAY 1.446809 (-5450 3500);
PAINT GREEN (-5450 3500);
DISPLAY INVISIBLE (-5450 3500);
FORCEPROP 1 LAST HDL_TAP TRUE
J 2
(-5775 3325);
DISPLAY 1.446809 (-5775 3325);
PAINT GREEN (-5775 3325);
DISPLAY INVISIBLE (-5775 3325);
FORCEPROP 1 LAST PATH I94
J 2
(-5448 3450);
DISPLAY 0.872340 (-5448 3450);
PAINT GREEN (-5448 3450);
DISPLAY INVISIBLE (-5448 3450);
FORCEADD TAP..1
R 2
(-5450 3400);
FORCEPROP 3 LASTPIN (-5400 3400) SIG_NAME P3E_CPU0_PE2_SS_RXP<12>
J 0
(-5390 3410);
DISPLAY 0.659574 (-5390 3410);
PAINT MONO (-5390 3410);
DISPLAY INVISIBLE (-5390 3410);
FORCEPROP 1 LASTPIN (-5400 3400) BN 12
J 2
(-5388 3408);
DISPLAY 0.617021 (-5388 3408);
PAINT PINK (-5388 3408);
FORCEPROP 2 LAST CDS_LIB mstr_standard
J 0
(-5450 3400);
PAINT MONO (-5450 3400);
DISPLAY INVISIBLE (-5450 3400);
FORCEPROP 1 LAST BODY_TYPE PLUMBING
J 2
(-5450 3450);
DISPLAY 1.446809 (-5450 3450);
PAINT GREEN (-5450 3450);
DISPLAY INVISIBLE (-5450 3450);
FORCEPROP 1 LAST HDL_TAP TRUE
J 2
(-5775 3275);
DISPLAY 1.446809 (-5775 3275);
PAINT GREEN (-5775 3275);
DISPLAY INVISIBLE (-5775 3275);
FORCEPROP 1 LAST PATH I95
J 2
(-5448 3400);
DISPLAY 0.872340 (-5448 3400);
PAINT GREEN (-5448 3400);
DISPLAY INVISIBLE (-5448 3400);
FORCEADD TAP..1
R 2
(-5450 3050);
FORCEPROP 3 LASTPIN (-5400 3050) SIG_NAME P3E_CPU0_PE2_SS_RXP<11>
J 0
(-5390 3060);
DISPLAY 0.659574 (-5390 3060);
PAINT MONO (-5390 3060);
DISPLAY INVISIBLE (-5390 3060);
FORCEPROP 1 LASTPIN (-5400 3050) BN 11
J 2
(-5388 3058);
DISPLAY 0.617021 (-5388 3058);
PAINT PINK (-5388 3058);
FORCEPROP 2 LAST CDS_LIB mstr_standard
J 0
(-5450 3050);
PAINT MONO (-5450 3050);
DISPLAY INVISIBLE (-5450 3050);
FORCEPROP 1 LAST BODY_TYPE PLUMBING
J 2
(-5450 3100);
DISPLAY 1.446809 (-5450 3100);
PAINT GREEN (-5450 3100);
DISPLAY INVISIBLE (-5450 3100);
FORCEPROP 1 LAST HDL_TAP TRUE
J 2
(-5775 2925);
DISPLAY 1.446809 (-5775 2925);
PAINT GREEN (-5775 2925);
DISPLAY INVISIBLE (-5775 2925);
FORCEPROP 1 LAST PATH I96
J 2
(-5448 3050);
DISPLAY 0.872340 (-5448 3050);
PAINT GREEN (-5448 3050);
DISPLAY INVISIBLE (-5448 3050);
FORCEADD TAP..1
R 2
(-5300 2800);
FORCEPROP 3 LASTPIN (-5250 2800) SIG_NAME P3E_CPU0_PE2_SS_RXN<11>
J 0
(-5240 2810);
DISPLAY 0.659574 (-5240 2810);
PAINT MONO (-5240 2810);
DISPLAY INVISIBLE (-5240 2810);
FORCEPROP 1 LASTPIN (-5250 2800) BN 11
J 2
(-5238 2808);
DISPLAY 0.617021 (-5238 2808);
PAINT PINK (-5238 2808);
FORCEPROP 2 LAST CDS_LIB mstr_standard
J 0
(-5300 2800);
PAINT MONO (-5300 2800);
DISPLAY INVISIBLE (-5300 2800);
FORCEPROP 1 LAST BODY_TYPE PLUMBING
J 2
(-5300 2850);
DISPLAY 1.446809 (-5300 2850);
PAINT GREEN (-5300 2850);
DISPLAY INVISIBLE (-5300 2850);
FORCEPROP 1 LAST HDL_TAP TRUE
J 2
(-5625 2675);
DISPLAY 1.446809 (-5625 2675);
PAINT GREEN (-5625 2675);
DISPLAY INVISIBLE (-5625 2675);
FORCEPROP 1 LAST PATH I97
J 2
(-5298 2800);
DISPLAY 0.872340 (-5298 2800);
PAINT GREEN (-5298 2800);
DISPLAY INVISIBLE (-5298 2800);
FORCEADD TAP..1
R 2
(-5300 2700);
FORCEPROP 3 LASTPIN (-5250 2700) SIG_NAME P3E_CPU0_PE2_SS_RXN<9>
J 0
(-5240 2710);
DISPLAY 0.659574 (-5240 2710);
PAINT MONO (-5240 2710);
DISPLAY INVISIBLE (-5240 2710);
FORCEPROP 1 LASTPIN (-5250 2700) BN 9
J 2
(-5238 2708);
DISPLAY 0.617021 (-5238 2708);
PAINT PINK (-5238 2708);
FORCEPROP 2 LAST CDS_LIB mstr_standard
J 0
(-5300 2700);
PAINT MONO (-5300 2700);
DISPLAY INVISIBLE (-5300 2700);
FORCEPROP 1 LAST BODY_TYPE PLUMBING
J 2
(-5300 2750);
DISPLAY 1.446809 (-5300 2750);
PAINT GREEN (-5300 2750);
DISPLAY INVISIBLE (-5300 2750);
FORCEPROP 1 LAST HDL_TAP TRUE
J 2
(-5625 2575);
DISPLAY 1.446809 (-5625 2575);
PAINT GREEN (-5625 2575);
DISPLAY INVISIBLE (-5625 2575);
FORCEPROP 1 LAST PATH I98
J 2
(-5298 2700);
DISPLAY 0.872340 (-5298 2700);
PAINT GREEN (-5298 2700);
DISPLAY INVISIBLE (-5298 2700);
FORCEADD TAP..1
R 2
(-5300 2750);
FORCEPROP 3 LASTPIN (-5250 2750) SIG_NAME P3E_CPU0_PE2_SS_RXN<10>
J 0
(-5240 2760);
DISPLAY 0.659574 (-5240 2760);
PAINT MONO (-5240 2760);
DISPLAY INVISIBLE (-5240 2760);
FORCEPROP 1 LASTPIN (-5250 2750) BN 10
J 2
(-5238 2758);
DISPLAY 0.617021 (-5238 2758);
PAINT PINK (-5238 2758);
FORCEPROP 2 LAST CDS_LIB mstr_standard
J 0
(-5300 2750);
PAINT MONO (-5300 2750);
DISPLAY INVISIBLE (-5300 2750);
FORCEPROP 1 LAST BODY_TYPE PLUMBING
J 2
(-5300 2800);
DISPLAY 1.446809 (-5300 2800);
PAINT GREEN (-5300 2800);
DISPLAY INVISIBLE (-5300 2800);
FORCEPROP 1 LAST HDL_TAP TRUE
J 2
(-5625 2625);
DISPLAY 1.446809 (-5625 2625);
PAINT GREEN (-5625 2625);
DISPLAY INVISIBLE (-5625 2625);
FORCEPROP 1 LAST PATH I99
J 2
(-5298 2750);
DISPLAY 0.872340 (-5298 2750);
PAINT GREEN (-5298 2750);
DISPLAY INVISIBLE (-5298 2750);
FORCEADD PRELIM..10
(-4015 2590);
PAINT GRAY (-4015 2590);
FORCEPROP 2 LAST CDS_LIB mstr_misc
J 0
(-4015 2590);
PAINT ORANGE (-4015 2590);
DISPLAY INVISIBLE (-4015 2590);
FORCEPROP 1 LAST COMMENT_BODY TRUE
J 0
(-4015 2590);
PAINT ORANGE (-4015 2590);
DISPLAY INVISIBLE (-4015 2590);
FORCEADD INTEL_CORP_BPAGE..1
(0 0);
FORCEPROP 1 LAST CDS_CON_LAST_MODIFIED Fri Jun 16 17:48:12 2017
J 0
(-1425 325);
DISPLAY 1.340426 (-1425 325);
PAINT GREEN (-1425 325);
DISPLAY INVISIBLE (-1425 325);
FORCEPROP 1 LAST CUSTOM_TXT_CDS <CURRENT_DESIGN_SHEET> OF <TOTAL_DESIGN_SHEETS>
J 0
(-500 25);
PAINT ORANGE (-500 25);
FORCEPROP 1 LAST CUSTOM_TXT_CDS <CON_LAST_MODIFIED>
J 0
(-4000 100);
PAINT ORANGE (-4000 100);
FORCEPROP 2 LAST CUSTOM_TXT_CDS <XR_PAGE_TITLE>
J 0
(-7890 5250);
DISPLAY 0.638298 (-7890 5250);
PAINT PINK (-7890 5250);
DISPLAY INVISIBLE (-7890 5250);
FORCEPROP 1 LAST SCH_TITLE SKYLAKE - SKT0 - 11 OF 21
J 0
(-7950 50);
DISPLAY 1.212766 (-7950 50);
PAINT GREEN (-7950 50);
FORCEPROP 2 LAST PAGE_BORDER TRUE
J 0
(-7890 5250);
DISPLAY 0.851064 (-7890 5250);
PAINT PINK (-7890 5250);
DISPLAY INVISIBLE (-7890 5250);
FORCEPROP 2 LAST CDS_LIB mstr_symbols
J 0
(0 0);
PAINT ORANGE (0 0);
DISPLAY INVISIBLE (0 0);
FORCEPROP 1 LAST COMMENT_BODY TRUE
J 0
(12 12);
DISPLAY 0.638298 (12 12);
PAINT GREEN (12 12);
DISPLAY INVISIBLE (12 12);
FORCEPROP 2 LAST CDS_XR_PAGE_TITLE CR-31 : @BASEBOARD_FAB2_LIB.BASEBOARD_FAB2(SCH_1):PAGE31
J 0
(-7890 5250);
DISPLAY 0.638298 (-7890 5250);
PAINT PINK (-7890 5250);
DISPLAY INVISIBLE (-7890 5250);
FORCEADD DESIGN_NOTE..1
(-4550 1325);
FORCEPROP 0 LAST L1 CPU SYMBOLS 1-30 ARE PRELIMINARY AND SUBJECT TO CHANGE
J 0
(-4750 1200);
DISPLAY 1.021277 (-4750 1200);
PAINT ORANGE (-4750 1200);
FORCEPROP 2 LAST CDS_LIB mstr_symbols
J 0
(-4550 1325);
PAINT ORANGE (-4550 1325);
DISPLAY INVISIBLE (-4550 1325);
FORCEPROP 1 LAST COMMENT_BODY TRUE
J 0
(-4525 1425);
DISPLAY 0.978723 (-4525 1425);
PAINT ORANGE (-4525 1425);
DISPLAY INVISIBLE (-4525 1425);
WIRE 17 -1 (-2625 1675)(-2625 1725);
WIRE 17 -1 (-2625 1725)(-2625 1775);
WIRE 17 -1 (-2625 1775)(-2625 1825);
WIRE 17 -1 (-2625 2175)(-2625 1825);
WIRE 17 -1 (-2625 2175)(-2625 2225);
WIRE 17 -1 (-2625 2225)(-2625 2275);
WIRE 17 -1 (-2625 2275)(-2625 2325);
WIRE 17 -1 (-2625 2325)(-2625 2675);
WIRE 17 -1 (-2625 2675)(-2625 2725);
WIRE 17 -1 (-2625 2725)(-2625 2775);
WIRE 17 -1 (-2625 2775)(-2625 2825);
WIRE 17 -1 (-2625 3175)(-2625 2825);
WIRE 17 -1 (-2625 3175)(-2625 3225);
WIRE 17 -1 (-2625 3575)(-1775 3575);
FORCEPROP 2 LAST SIG_NAME P3E_CPU0_PE2_SS_TXN<15:0>
J 0
(-2525 3585);
DISPLAY 0.617021 (-2525 3585);
PAINT ORANGE (-2525 3585);
WIRE 17 -1 (-2625 3575)(-2625 3325);
WIRE 17 -1 (-2625 3225)(-2625 3275);
WIRE 17 -1 (-2625 3275)(-2625 3325);
WIRE 17 -1 (-2775 1925)(-2775 1975);
WIRE 17 -1 (-2775 1975)(-2775 2025);
WIRE 17 -1 (-2775 2025)(-2775 2075);
WIRE 17 -1 (-2775 2075)(-2775 2425);
WIRE 17 -1 (-2775 2425)(-2775 2475);
WIRE 17 -1 (-2775 2475)(-2775 2525);
WIRE 17 -1 (-2775 2525)(-2775 2575);
WIRE 17 -1 (-2775 2925)(-2775 2575);
WIRE 17 -1 (-2775 2925)(-2775 2975);
WIRE 17 -1 (-2775 2975)(-2775 3025);
WIRE 17 -1 (-2775 3075)(-2775 3025);
WIRE 17 -1 (-2775 3425)(-2775 3075);
WIRE 17 -1 (-2775 3425)(-2775 3475);
WIRE 17 -1 (-2775 3625)(-1775 3625);
FORCEPROP 2 LAST SIG_NAME P3E_CPU0_PE2_SS_TXP<15:0>
J 0
(-2525 3635);
DISPLAY 0.617021 (-2525 3635);
PAINT ORANGE (-2525 3635);
WIRE 17 -1 (-2775 3625)(-2775 3575);
WIRE 17 -1 (-2775 3475)(-2775 3525);
WIRE 17 -1 (-2775 3525)(-2775 3575);
WIRE 17 -1 (-5350 1725)(-5350 1675);
WIRE 17 -1 (-5350 1725)(-5350 1775);
WIRE 17 -1 (-5350 1775)(-5350 1825);
WIRE 17 -1 (-5350 2175)(-5350 1825);
WIRE 17 -1 (-5350 2225)(-5350 2175);
WIRE 17 -1 (-5350 2275)(-5350 2225);
WIRE 17 -1 (-5350 2325)(-5350 2275);
WIRE 17 -1 (-5350 2325)(-5350 2675);
WIRE 17 -1 (-5350 2725)(-5350 2675);
WIRE 17 -1 (-5350 2725)(-5350 2775);
WIRE 17 -1 (-5350 2775)(-5350 2825);
WIRE 17 -1 (-5350 3175)(-5350 2825);
WIRE 17 -1 (-5350 3225)(-5350 3175);
WIRE 17 -1 (-5350 3275)(-5350 3225);
WIRE 17 -1 (-5350 3325)(-5350 3275);
WIRE 17 -1 (-6550 3650)(-5350 3650);
FORCEPROP 2 LAST SIG_NAME P3E_CPU0_PE2_SS_RXN<15:0>
J 0
(-6535 3660);
DISPLAY 0.617021 (-6535 3660);
PAINT ORANGE (-6535 3660);
WIRE 17 -1 (-5350 3650)(-5350 3325);
WIRE 17 -1 (-5500 1925)(-5500 1975);
WIRE 17 -1 (-5500 2025)(-5500 1975);
WIRE 17 -1 (-5500 2075)(-5500 2025);
WIRE 17 -1 (-5500 2425)(-5500 2075);
WIRE 17 -1 (-5500 2475)(-5500 2425);
WIRE 17 -1 (-5500 2525)(-5500 2475);
WIRE 17 -1 (-5500 2575)(-5500 2525);
WIRE 17 -1 (-5500 2575)(-5500 2925);
WIRE 17 -1 (-5500 2925)(-5500 2975);
WIRE 17 -1 (-5500 3025)(-5500 2975);
WIRE 17 -1 (-5500 3075)(-5500 3025);
WIRE 17 -1 (-5500 3425)(-5500 3075);
WIRE 17 -1 (-6550 3700)(-5500 3700);
FORCEPROP 2 LAST SIG_NAME P3E_CPU0_PE2_SS_RXP<15:0>
J 0
(-6535 3710);
DISPLAY 0.617021 (-6535 3710);
PAINT ORANGE (-6535 3710);
WIRE 17 -1 (-5500 3475)(-5500 3425);
WIRE 17 -1 (-5500 3525)(-5500 3475);
WIRE 17 -1 (-5500 3700)(-5500 3575);
WIRE 17 -1 (-5500 3575)(-5500 3525);
WIRE 16 -1 (-2725 3250)(-3275 3250);
WIRE 16 -1 (-5400 3550)(-4775 3550);
WIRE 16 -1 (-4775 2900)(-5400 2900);
WIRE 16 -1 (-4775 3000)(-5400 3000);
WIRE 16 -1 (-5400 2950)(-4775 2950);
WIRE 16 -1 (-4775 1750)(-5250 1750);
WIRE 16 -1 (-4775 1900)(-5400 1900);
WIRE 16 -1 (-5400 1950)(-4775 1950);
WIRE 16 -1 (-4775 2000)(-5400 2000);
WIRE 16 -1 (-4775 1650)(-5250 1650);
WIRE 16 -1 (-4775 1700)(-5250 1700);
WIRE 16 -1 (-5250 1800)(-4775 1800);
WIRE 16 -1 (-5400 2050)(-4775 2050);
WIRE 16 -1 (-4775 2400)(-5400 2400);
WIRE 16 -1 (-5400 2450)(-4775 2450);
WIRE 16 -1 (-4775 2500)(-5400 2500);
WIRE 16 -1 (-5400 2550)(-4775 2550);
WIRE 16 -1 (-5400 3050)(-4775 3050);
WIRE 16 -1 (-4775 3400)(-5400 3400);
WIRE 16 -1 (-5400 3450)(-4775 3450);
WIRE 16 -1 (-4775 3500)(-5400 3500);
WIRE 16 -1 (-4775 2150)(-5250 2150);
WIRE 16 -1 (-5250 2200)(-4775 2200);
WIRE 16 -1 (-4775 2250)(-5250 2250);
WIRE 16 -1 (-5250 2300)(-4775 2300);
WIRE 16 -1 (-4775 2650)(-5250 2650);
WIRE 16 -1 (-4775 2700)(-5250 2700);
WIRE 16 -1 (-4775 2750)(-5250 2750);
WIRE 16 -1 (-5250 2800)(-4775 2800);
WIRE 16 -1 (-4775 3150)(-5250 3150);
WIRE 16 -1 (-5250 3200)(-4775 3200);
WIRE 16 -1 (-4775 3250)(-5250 3250);
WIRE 16 -1 (-5250 3300)(-4775 3300);
WIRE 16 -1 (-2875 1900)(-3275 1900);
WIRE 16 -1 (-3275 1950)(-2875 1950);
WIRE 16 -1 (-3275 2000)(-2875 2000);
WIRE 16 -1 (-2725 1650)(-3275 1650);
WIRE 16 -1 (-3275 1700)(-2725 1700);
WIRE 16 -1 (-2725 1750)(-3275 1750);
WIRE 16 -1 (-3275 1800)(-2725 1800);
WIRE 16 -1 (-2875 2050)(-3275 2050);
WIRE 16 -1 (-2875 2400)(-3275 2400);
WIRE 16 -1 (-2875 2450)(-3275 2450);
WIRE 16 -1 (-2875 2500)(-3275 2500);
WIRE 16 -1 (-2875 2550)(-3275 2550);
WIRE 16 -1 (-2875 2900)(-3275 2900);
WIRE 16 -1 (-3275 2950)(-2875 2950);
WIRE 16 -1 (-3275 3000)(-2875 3000);
WIRE 16 -1 (-3275 3050)(-2875 3050);
WIRE 16 -1 (-2875 3400)(-3275 3400);
WIRE 16 -1 (-2875 3450)(-3275 3450);
WIRE 16 -1 (-2875 3500)(-3275 3500);
WIRE 16 -1 (-2875 3550)(-3275 3550);
WIRE 16 -1 (-2725 2150)(-3275 2150);
WIRE 16 -1 (-2725 2200)(-3275 2200);
WIRE 16 -1 (-3275 2250)(-2725 2250);
WIRE 16 -1 (-3275 2300)(-2725 2300);
WIRE 16 -1 (-3275 2650)(-2725 2650);
WIRE 16 -1 (-2725 2700)(-3275 2700);
WIRE 16 -1 (-3275 2750)(-2725 2750);
WIRE 16 -1 (-3275 2800)(-2725 2800);
WIRE 16 -1 (-3275 3150)(-2725 3150);
WIRE 16 -1 (-3275 3200)(-2725 3200);
WIRE 16 -1 (-2725 3300)(-3275 3300);
FORCENOTE
FROM X24 SUPER SLOT
(-6700 3500) 0;
DISPLAY LEFT (-6700 3500);
DISPLAY 1.021277 (-6700 3500);
PAINT PURPLE (-6700 3500);
FORCENOTE
TO X24 SUPER SLOT
(-2225 3425) 0;
DISPLAY LEFT (-2225 3425);
DISPLAY 1.021277 (-2225 3425);
PAINT PURPLE (-2225 3425);
FORCENOTE
SKYLAKE - SKT0 - 11 OF 21
(-1650 150) 0;
DISPLAY LEFT (-1650 150);
DISPLAY 1.021277 (-1650 150);
PAINT RED (-1650 150);
FORCENOTE
ROOM=CPU0
(-7925 350) 0;
DISPLAY LEFT (-7925 350);
DISPLAY 1.723404 (-7925 350);
PAINT PURPLE (-7925 350);
FORCENOTE
BOM_COST=PROC_SOCKET
(-7925 225) 0;
DISPLAY LEFT (-7925 225);
DISPLAY 1.723404 (-7925 225);
PAINT PURPLE (-7925 225);
QUIT
